FILE_TYPE = MACRO_DRAWING;
SET COLOR_WIRE YELLOW;
SET COLOR_PROP MONO;
SET COLOR_DOT WHITE;
SET COLOR_ARC YELLOW;
SET COLOR_BODY GREEN;
SET COLOR_NOTE MONO;
SET PROP_DISPLAY VALUE;
SET PAGE_NUMBER P88;
FORCEADD OFFPAGE..3
(1600 5200);
FORCEPROP 2 LAST $XR0 62 
J 0
(1814 5200);
DISPLAY 0.638298 (1814 5200);
PAINT MONO (1814 5200);
FORCEPROP 2 LAST $XR1 87 
J 0
(1904 5200);
DISPLAY 0.638298 (1904 5200);
PAINT MONO (1904 5200);
FORCEPROP 2 LAST CDS_LIB mstr_standard
J 0
(1600 5200);
DISPLAY 0.787234 (1600 5200);
PAINT MONO (1600 5200);
DISPLAY INVISIBLE (1600 5200);
FORCEPROP 1 LAST OFFPAGE TRUE
J 0
(1925 5075);
DISPLAY 0.936170 (1925 5075);
PAINT GREEN (1925 5075);
DISPLAY INVISIBLE (1925 5075);
FORCEPROP 1 LAST COMMENT_BODY TRUE
J 0
(1550 5100);
DISPLAY 0.936170 (1550 5100);
PAINT GREEN (1550 5100);
DISPLAY INVISIBLE (1550 5100);
FORCEPROP 2 LAST PATH I1
J 0
(1800 5275);
DISPLAY 0.787234 (1800 5275);
PAINT MONO (1800 5275);
DISPLAY INVISIBLE (1800 5275);
FORCEADD TAP..6
R 2
(-1700 2050);
FORCEPROP 3 LASTPIN (-1750 2050) SIG_NAME M_M_DQ<9>
J 0
(-1740 2060);
DISPLAY 0.659574 (-1740 2060);
PAINT MONO (-1740 2060);
DISPLAY INVISIBLE (-1740 2060);
FORCEPROP 1 LASTPIN (-1750 2050) BN 9
J 2
(-1700 2060);
DISPLAY 0.617021 (-1700 2060);
PAINT PINK (-1700 2060);
FORCEPROP 2 LAST CDS_LIB mstr_standard
J 2
(-1700 2050);
DISPLAY 0.787234 (-1700 2050);
PAINT MONO (-1700 2050);
DISPLAY INVISIBLE (-1700 2050);
FORCEPROP 1 LAST BODY_TYPE PLUMBING
J 2
(-1700 2000);
DISPLAY 1.234043 (-1700 2000);
PAINT GREEN (-1700 2000);
DISPLAY INVISIBLE (-1700 2000);
FORCEPROP 1 LAST HDL_TAP TRUE
J 2
(-2025 1925);
DISPLAY 1.234043 (-2025 1925);
PAINT GREEN (-2025 1925);
DISPLAY INVISIBLE (-2025 1925);
FORCEPROP 1 LAST PATH I100
J 2
(-1700 2050);
DISPLAY 0.936170 (-1700 2050);
PAINT GREEN (-1700 2050);
DISPLAY INVISIBLE (-1700 2050);
FORCEADD TAP..6
R 2
(-1700 2150);
FORCEPROP 3 LASTPIN (-1750 2150) SIG_NAME M_M_DQ<11>
J 0
(-1740 2160);
DISPLAY 0.659574 (-1740 2160);
PAINT MONO (-1740 2160);
DISPLAY INVISIBLE (-1740 2160);
FORCEPROP 1 LASTPIN (-1750 2150) BN 11
J 2
(-1700 2160);
DISPLAY 0.617021 (-1700 2160);
PAINT PINK (-1700 2160);
FORCEPROP 2 LAST CDS_LIB mstr_standard
J 2
(-1700 2150);
DISPLAY 0.787234 (-1700 2150);
PAINT MONO (-1700 2150);
DISPLAY INVISIBLE (-1700 2150);
FORCEPROP 1 LAST BODY_TYPE PLUMBING
J 2
(-1700 2100);
DISPLAY 1.234043 (-1700 2100);
PAINT GREEN (-1700 2100);
DISPLAY INVISIBLE (-1700 2100);
FORCEPROP 1 LAST HDL_TAP TRUE
J 2
(-2025 2025);
DISPLAY 1.234043 (-2025 2025);
PAINT GREEN (-2025 2025);
DISPLAY INVISIBLE (-2025 2025);
FORCEPROP 1 LAST PATH I101
J 2
(-1700 2150);
DISPLAY 0.936170 (-1700 2150);
PAINT GREEN (-1700 2150);
DISPLAY INVISIBLE (-1700 2150);
FORCEADD TAP..6
R 2
(-1700 2200);
FORCEPROP 3 LASTPIN (-1750 2200) SIG_NAME M_M_DQ<12>
J 0
(-1740 2210);
DISPLAY 0.659574 (-1740 2210);
PAINT MONO (-1740 2210);
DISPLAY INVISIBLE (-1740 2210);
FORCEPROP 1 LASTPIN (-1750 2200) BN 12
J 2
(-1700 2210);
DISPLAY 0.617021 (-1700 2210);
PAINT PINK (-1700 2210);
FORCEPROP 2 LAST CDS_LIB mstr_standard
J 2
(-1700 2200);
DISPLAY 0.787234 (-1700 2200);
PAINT MONO (-1700 2200);
DISPLAY INVISIBLE (-1700 2200);
FORCEPROP 1 LAST BODY_TYPE PLUMBING
J 2
(-1700 2150);
DISPLAY 1.234043 (-1700 2150);
PAINT GREEN (-1700 2150);
DISPLAY INVISIBLE (-1700 2150);
FORCEPROP 1 LAST HDL_TAP TRUE
J 2
(-2025 2075);
DISPLAY 1.234043 (-2025 2075);
PAINT GREEN (-2025 2075);
DISPLAY INVISIBLE (-2025 2075);
FORCEPROP 1 LAST PATH I102
J 2
(-1700 2200);
DISPLAY 0.936170 (-1700 2200);
PAINT GREEN (-1700 2200);
DISPLAY INVISIBLE (-1700 2200);
FORCEADD TAP..6
R 2
(-1700 1950);
FORCEPROP 3 LASTPIN (-1750 1950) SIG_NAME M_M_DQ<7>
J 0
(-1740 1960);
DISPLAY 0.659574 (-1740 1960);
PAINT MONO (-1740 1960);
DISPLAY INVISIBLE (-1740 1960);
FORCEPROP 1 LASTPIN (-1750 1950) BN 7
J 2
(-1700 1960);
DISPLAY 0.617021 (-1700 1960);
PAINT PINK (-1700 1960);
FORCEPROP 2 LAST CDS_LIB mstr_standard
J 2
(-1700 1950);
DISPLAY 0.787234 (-1700 1950);
PAINT MONO (-1700 1950);
DISPLAY INVISIBLE (-1700 1950);
FORCEPROP 1 LAST BODY_TYPE PLUMBING
J 2
(-1700 1900);
DISPLAY 1.234043 (-1700 1900);
PAINT GREEN (-1700 1900);
DISPLAY INVISIBLE (-1700 1900);
FORCEPROP 1 LAST HDL_TAP TRUE
J 2
(-2025 1825);
DISPLAY 1.234043 (-2025 1825);
PAINT GREEN (-2025 1825);
DISPLAY INVISIBLE (-2025 1825);
FORCEPROP 1 LAST PATH I103
J 2
(-1700 1950);
DISPLAY 0.936170 (-1700 1950);
PAINT GREEN (-1700 1950);
DISPLAY INVISIBLE (-1700 1950);
FORCEADD TAP..6
R 2
(-1700 1900);
FORCEPROP 3 LASTPIN (-1750 1900) SIG_NAME M_M_DQ<6>
J 0
(-1740 1910);
DISPLAY 0.659574 (-1740 1910);
PAINT MONO (-1740 1910);
DISPLAY INVISIBLE (-1740 1910);
FORCEPROP 1 LASTPIN (-1750 1900) BN 6
J 2
(-1700 1910);
DISPLAY 0.617021 (-1700 1910);
PAINT PINK (-1700 1910);
FORCEPROP 2 LAST CDS_LIB mstr_standard
J 2
(-1700 1900);
DISPLAY 0.787234 (-1700 1900);
PAINT MONO (-1700 1900);
DISPLAY INVISIBLE (-1700 1900);
FORCEPROP 1 LAST BODY_TYPE PLUMBING
J 2
(-1700 1850);
DISPLAY 1.234043 (-1700 1850);
PAINT GREEN (-1700 1850);
DISPLAY INVISIBLE (-1700 1850);
FORCEPROP 1 LAST HDL_TAP TRUE
J 2
(-2025 1775);
DISPLAY 1.234043 (-2025 1775);
PAINT GREEN (-2025 1775);
DISPLAY INVISIBLE (-2025 1775);
FORCEPROP 1 LAST PATH I104
J 2
(-1700 1900);
DISPLAY 0.936170 (-1700 1900);
PAINT GREEN (-1700 1900);
DISPLAY INVISIBLE (-1700 1900);
FORCEADD TAP..6
R 2
(-1700 1850);
FORCEPROP 3 LASTPIN (-1750 1850) SIG_NAME M_M_DQ<5>
J 0
(-1740 1860);
DISPLAY 0.659574 (-1740 1860);
PAINT MONO (-1740 1860);
DISPLAY INVISIBLE (-1740 1860);
FORCEPROP 1 LASTPIN (-1750 1850) BN 5
J 2
(-1700 1860);
DISPLAY 0.617021 (-1700 1860);
PAINT PINK (-1700 1860);
FORCEPROP 2 LAST CDS_LIB mstr_standard
J 2
(-1700 1850);
DISPLAY 0.787234 (-1700 1850);
PAINT MONO (-1700 1850);
DISPLAY INVISIBLE (-1700 1850);
FORCEPROP 1 LAST BODY_TYPE PLUMBING
J 2
(-1700 1800);
DISPLAY 1.234043 (-1700 1800);
PAINT GREEN (-1700 1800);
DISPLAY INVISIBLE (-1700 1800);
FORCEPROP 1 LAST HDL_TAP TRUE
J 2
(-2025 1725);
DISPLAY 1.234043 (-2025 1725);
PAINT GREEN (-2025 1725);
DISPLAY INVISIBLE (-2025 1725);
FORCEPROP 1 LAST PATH I105
J 2
(-1700 1850);
DISPLAY 0.936170 (-1700 1850);
PAINT GREEN (-1700 1850);
DISPLAY INVISIBLE (-1700 1850);
FORCEADD TAP..6
R 2
(-1700 1800);
FORCEPROP 3 LASTPIN (-1750 1800) SIG_NAME M_M_DQ<4>
J 0
(-1740 1810);
DISPLAY 0.659574 (-1740 1810);
PAINT MONO (-1740 1810);
DISPLAY INVISIBLE (-1740 1810);
FORCEPROP 1 LASTPIN (-1750 1800) BN 4
J 2
(-1700 1810);
DISPLAY 0.617021 (-1700 1810);
PAINT PINK (-1700 1810);
FORCEPROP 2 LAST CDS_LIB mstr_standard
J 2
(-1700 1800);
DISPLAY 0.787234 (-1700 1800);
PAINT MONO (-1700 1800);
DISPLAY INVISIBLE (-1700 1800);
FORCEPROP 1 LAST BODY_TYPE PLUMBING
J 2
(-1700 1750);
DISPLAY 1.234043 (-1700 1750);
PAINT GREEN (-1700 1750);
DISPLAY INVISIBLE (-1700 1750);
FORCEPROP 1 LAST HDL_TAP TRUE
J 2
(-2025 1675);
DISPLAY 1.234043 (-2025 1675);
PAINT GREEN (-2025 1675);
DISPLAY INVISIBLE (-2025 1675);
FORCEPROP 1 LAST PATH I106
J 2
(-1700 1800);
DISPLAY 0.936170 (-1700 1800);
PAINT GREEN (-1700 1800);
DISPLAY INVISIBLE (-1700 1800);
FORCEADD TAP..6
R 2
(-1700 1750);
FORCEPROP 3 LASTPIN (-1750 1750) SIG_NAME M_M_DQ<3>
J 0
(-1740 1760);
DISPLAY 0.659574 (-1740 1760);
PAINT MONO (-1740 1760);
DISPLAY INVISIBLE (-1740 1760);
FORCEPROP 1 LASTPIN (-1750 1750) BN 3
J 2
(-1700 1760);
DISPLAY 0.617021 (-1700 1760);
PAINT PINK (-1700 1760);
FORCEPROP 2 LAST CDS_LIB mstr_standard
J 2
(-1700 1750);
DISPLAY 0.787234 (-1700 1750);
PAINT MONO (-1700 1750);
DISPLAY INVISIBLE (-1700 1750);
FORCEPROP 1 LAST BODY_TYPE PLUMBING
J 2
(-1700 1700);
DISPLAY 1.234043 (-1700 1700);
PAINT GREEN (-1700 1700);
DISPLAY INVISIBLE (-1700 1700);
FORCEPROP 1 LAST HDL_TAP TRUE
J 2
(-2025 1625);
DISPLAY 1.234043 (-2025 1625);
PAINT GREEN (-2025 1625);
DISPLAY INVISIBLE (-2025 1625);
FORCEPROP 1 LAST PATH I107
J 2
(-1700 1750);
DISPLAY 0.936170 (-1700 1750);
PAINT GREEN (-1700 1750);
DISPLAY INVISIBLE (-1700 1750);
FORCEADD TAP..6
R 2
(-1700 1600);
FORCEPROP 3 LASTPIN (-1750 1600) SIG_NAME M_M_DQ<0>
J 0
(-1740 1610);
DISPLAY 0.659574 (-1740 1610);
PAINT MONO (-1740 1610);
DISPLAY INVISIBLE (-1740 1610);
FORCEPROP 1 LASTPIN (-1750 1600) BN 0
J 2
(-1700 1610);
DISPLAY 0.617021 (-1700 1610);
PAINT PINK (-1700 1610);
FORCEPROP 2 LAST CDS_LIB mstr_standard
J 2
(-1700 1600);
DISPLAY 0.787234 (-1700 1600);
PAINT MONO (-1700 1600);
DISPLAY INVISIBLE (-1700 1600);
FORCEPROP 1 LAST BODY_TYPE PLUMBING
J 2
(-1700 1550);
DISPLAY 1.234043 (-1700 1550);
PAINT GREEN (-1700 1550);
DISPLAY INVISIBLE (-1700 1550);
FORCEPROP 1 LAST HDL_TAP TRUE
J 2
(-2025 1475);
DISPLAY 1.234043 (-2025 1475);
PAINT GREEN (-2025 1475);
DISPLAY INVISIBLE (-2025 1475);
FORCEPROP 1 LAST PATH I108
J 2
(-1700 1600);
DISPLAY 0.936170 (-1700 1600);
PAINT GREEN (-1700 1600);
DISPLAY INVISIBLE (-1700 1600);
FORCEADD TAP..6
R 2
(-1700 1700);
FORCEPROP 3 LASTPIN (-1750 1700) SIG_NAME M_M_DQ<2>
J 0
(-1740 1710);
DISPLAY 0.659574 (-1740 1710);
PAINT MONO (-1740 1710);
DISPLAY INVISIBLE (-1740 1710);
FORCEPROP 1 LASTPIN (-1750 1700) BN 2
J 2
(-1700 1710);
DISPLAY 0.617021 (-1700 1710);
PAINT PINK (-1700 1710);
FORCEPROP 2 LAST CDS_LIB mstr_standard
J 2
(-1700 1700);
DISPLAY 0.787234 (-1700 1700);
PAINT MONO (-1700 1700);
DISPLAY INVISIBLE (-1700 1700);
FORCEPROP 1 LAST BODY_TYPE PLUMBING
J 2
(-1700 1650);
DISPLAY 1.234043 (-1700 1650);
PAINT GREEN (-1700 1650);
DISPLAY INVISIBLE (-1700 1650);
FORCEPROP 1 LAST HDL_TAP TRUE
J 2
(-2025 1575);
DISPLAY 1.234043 (-2025 1575);
PAINT GREEN (-2025 1575);
DISPLAY INVISIBLE (-2025 1575);
FORCEPROP 1 LAST PATH I109
J 2
(-1700 1700);
DISPLAY 0.936170 (-1700 1700);
PAINT GREEN (-1700 1700);
DISPLAY INVISIBLE (-1700 1700);
FORCEADD PVDDQ_KLM..1
(-1350 2550);
FORCEPROP 3 LASTPIN (-1350 2500) SIG_NAME PVDDQ_KLM\g
J 0
(-1340 2510);
DISPLAY 0.659574 (-1340 2510);
PAINT MONO (-1340 2510);
DISPLAY INVISIBLE (-1340 2510);
FORCEPROP 1 LAST VOLTAGE 1.2V
J 0
(-1395 2507);
DISPLAY 0.340426 (-1395 2507);
PAINT SKYBLUE (-1395 2507);
DISPLAY INVISIBLE (-1395 2507);
FORCEPROP 2 LAST BOM_COST PROC
J 0
(-1350 2555);
PAINT ORANGE (-1350 2555);
DISPLAY INVISIBLE (-1350 2555);
FORCEPROP 2 LAST CDS_LIB mstr_symbols
J 0
(-1350 2550);
PAINT ORANGE (-1350 2550);
DISPLAY INVISIBLE (-1350 2550);
FORCEPROP 1 LAST BODY_TYPE PLUMBING
J 0
(-1395 2507);
DISPLAY 0.340426 (-1395 2507);
PAINT GREEN (-1395 2507);
DISPLAY INVISIBLE (-1395 2507);
FORCEPROP 1 LAST PATH I11
J 0
(-1300 2575);
DISPLAY 0.872340 (-1300 2575);
PAINT AQUA (-1300 2575);
DISPLAY INVISIBLE (-1300 2575);
FORCEPROP 2 LAST ROOM PROC
J 0
(-1350 2650);
DISPLAY 0.787234 (-1350 2650);
PAINT ORANGE (-1350 2650);
DISPLAY INVISIBLE (-1350 2650);
FORCEPROP 1 LAST HDL_POWER PVDDQ_KLM
J 1
(-1350 2600);
DISPLAY 0.872340 (-1350 2600);
PAINT GREEN (-1350 2600);
DISPLAY INVISIBLE (-1350 2600);
FORCEADD TAP..6
R 2
(-1700 1650);
FORCEPROP 3 LASTPIN (-1750 1650) SIG_NAME M_M_DQ<1>
J 0
(-1740 1660);
DISPLAY 0.659574 (-1740 1660);
PAINT MONO (-1740 1660);
DISPLAY INVISIBLE (-1740 1660);
FORCEPROP 1 LASTPIN (-1750 1650) BN 1
J 2
(-1700 1660);
DISPLAY 0.617021 (-1700 1660);
PAINT PINK (-1700 1660);
FORCEPROP 2 LAST CDS_LIB mstr_standard
J 2
(-1700 1650);
DISPLAY 0.787234 (-1700 1650);
PAINT MONO (-1700 1650);
DISPLAY INVISIBLE (-1700 1650);
FORCEPROP 1 LAST BODY_TYPE PLUMBING
J 2
(-1700 1600);
DISPLAY 1.234043 (-1700 1600);
PAINT GREEN (-1700 1600);
DISPLAY INVISIBLE (-1700 1600);
FORCEPROP 1 LAST HDL_TAP TRUE
J 2
(-2025 1525);
DISPLAY 1.234043 (-2025 1525);
PAINT GREEN (-2025 1525);
DISPLAY INVISIBLE (-2025 1525);
FORCEPROP 1 LAST PATH I110
J 2
(-1700 1650);
DISPLAY 0.936170 (-1700 1650);
PAINT GREEN (-1700 1650);
DISPLAY INVISIBLE (-1700 1650);
FORCEADD SCONN288_H44441003..1
(-2450 3100);
FORCEPROP 1 LAST LOCATION J9L1
J 0
(-2900 5000);
DISPLAY 0.617021 (-2900 5000);
PAINT AQUA (-2900 5000);
FORCEPROP 1 LAST PART_NUMBER H44441-003
J 0
(-2900 1100);
DISPLAY 0.617021 (-2900 1100);
PAINT BLUE (-2900 1100);
FORCEPROP 1 LAST MATERIAL SCONN
J 0
(-2900 4950);
DISPLAY 0.617021 (-2900 4950);
PAINT SKYBLUE (-2900 4950);
FORCEPROP 2 LASTPIN (-2950 1600) $PN 146
J 2
(-2960 1610);
DISPLAY 0.617021 (-2960 1610);
PAINT ORANGE (-2960 1610);
FORCEPROP 2 LASTPIN (-2950 1950) $PN 284
J 2
(-2960 1960);
DISPLAY 0.617021 (-2960 1960);
PAINT ORANGE (-2960 1960);
FORCEPROP 2 LASTPIN (-2950 1750) $PN 285
J 2
(-2960 1760);
DISPLAY 0.617021 (-2960 1760);
PAINT ORANGE (-2960 1760);
FORCEPROP 2 LASTPIN (-2950 1700) $PN 141
J 2
(-2960 1710);
DISPLAY 0.617021 (-2960 1710);
PAINT ORANGE (-2960 1710);
FORCEPROP 2 LASTPIN (-2950 1300) $PN 230
J 2
(-2960 1310);
DISPLAY 0.617021 (-2960 1310);
PAINT ORANGE (-2960 1310);
FORCEPROP 2 LASTPIN (-2950 1900) $PN 238
J 2
(-2960 1910);
DISPLAY 0.617021 (-2960 1910);
PAINT ORANGE (-2960 1910);
FORCEPROP 2 LASTPIN (-2950 1850) $PN 140
J 2
(-2960 1860);
DISPLAY 0.617021 (-2960 1860);
PAINT ORANGE (-2960 1860);
FORCEPROP 2 LASTPIN (-2950 1800) $PN 139
J 2
(-2960 1810);
DISPLAY 0.617021 (-2960 1810);
PAINT ORANGE (-2960 1810);
FORCEPROP 2 LASTPIN (-2950 3250) $PN 237
J 2
(-2960 3260);
DISPLAY 0.617021 (-2960 3260);
PAINT ORANGE (-2960 3260);
FORCEPROP 2 LASTPIN (-2950 3200) $PN 93
J 2
(-2960 3210);
DISPLAY 0.617021 (-2960 3210);
PAINT ORANGE (-2960 3210);
FORCEPROP 2 LASTPIN (-2950 3150) $PN 89
J 2
(-2960 3160);
DISPLAY 0.617021 (-2960 3160);
PAINT ORANGE (-2960 3160);
FORCEPROP 2 LASTPIN (-2950 3100) $PN 84
J 2
(-2960 3110);
DISPLAY 0.617021 (-2960 3110);
PAINT ORANGE (-2960 3110);
FORCEPROP 2 LASTPIN (-2950 1500) $PN 144
J 2
(-2960 1510);
DISPLAY 0.617021 (-2960 1510);
PAINT ORANGE (-2960 1510);
FORCEPROP 2 LASTPIN (-2950 1450) $PN 227
J 2
(-2960 1460);
DISPLAY 0.617021 (-2960 1460);
PAINT ORANGE (-2960 1460);
FORCEPROP 2 LASTPIN (-2950 1400) $PN 205
J 2
(-2960 1410);
DISPLAY 0.617021 (-2960 1410);
PAINT ORANGE (-2960 1410);
FORCEPROP 2 LASTPIN (-2950 2200) $PN 58
J 2
(-2960 2210);
DISPLAY 0.617021 (-2960 2210);
PAINT ORANGE (-2960 2210);
FORCEPROP 2 LASTPIN (-2950 2250) $PN 222
J 2
(-2960 2260);
DISPLAY 0.617021 (-2960 2260);
PAINT ORANGE (-2960 2260);
FORCEPROP 2 LASTPIN (-2950 2850) $PN 91
J 2
(-2960 2860);
DISPLAY 0.617021 (-2960 2860);
PAINT ORANGE (-2960 2860);
FORCEPROP 2 LASTPIN (-2950 2800) $PN 87
J 2
(-2960 2810);
DISPLAY 0.617021 (-2960 2810);
PAINT ORANGE (-2960 2810);
FORCEPROP 2 LASTPIN (-2950 2150) $PN 78
J 2
(-2960 2160);
DISPLAY 0.617021 (-2960 2160);
PAINT ORANGE (-2960 2160);
FORCEPROP 2 LASTPIN (-1950 4750) $PN 280
J 0
(-1940 4760);
DISPLAY 0.617021 (-1940 4760);
PAINT ORANGE (-1940 4760);
FORCEPROP 2 LASTPIN (-1950 4700) $PN 135
J 0
(-1940 4710);
DISPLAY 0.617021 (-1940 4710);
PAINT ORANGE (-1940 4710);
FORCEPROP 2 LASTPIN (-1950 4650) $PN 273
J 0
(-1940 4660);
DISPLAY 0.617021 (-1940 4660);
PAINT ORANGE (-1940 4660);
FORCEPROP 2 LASTPIN (-1950 4600) $PN 128
J 0
(-1940 4610);
DISPLAY 0.617021 (-1940 4610);
PAINT ORANGE (-1940 4610);
FORCEPROP 2 LASTPIN (-1950 4550) $PN 282
J 0
(-1940 4560);
DISPLAY 0.617021 (-1940 4560);
PAINT ORANGE (-1940 4560);
FORCEPROP 2 LASTPIN (-1950 4500) $PN 137
J 0
(-1940 4510);
DISPLAY 0.617021 (-1940 4510);
PAINT ORANGE (-1940 4510);
FORCEPROP 2 LASTPIN (-1950 4450) $PN 275
J 0
(-1940 4460);
DISPLAY 0.617021 (-1940 4460);
PAINT ORANGE (-1940 4460);
FORCEPROP 2 LASTPIN (-1950 4400) $PN 130
J 0
(-1940 4410);
DISPLAY 0.617021 (-1940 4410);
PAINT ORANGE (-1940 4410);
FORCEPROP 2 LASTPIN (-1950 4350) $PN 269
J 0
(-1940 4360);
DISPLAY 0.617021 (-1940 4360);
PAINT ORANGE (-1940 4360);
FORCEPROP 2 LASTPIN (-1950 4300) $PN 124
J 0
(-1940 4310);
DISPLAY 0.617021 (-1940 4310);
PAINT ORANGE (-1940 4310);
FORCEPROP 2 LASTPIN (-1950 4250) $PN 262
J 0
(-1940 4260);
DISPLAY 0.617021 (-1940 4260);
PAINT ORANGE (-1940 4260);
FORCEPROP 2 LASTPIN (-1950 4200) $PN 117
J 0
(-1940 4210);
DISPLAY 0.617021 (-1940 4210);
PAINT ORANGE (-1940 4210);
FORCEPROP 2 LASTPIN (-1950 4150) $PN 271
J 0
(-1940 4160);
DISPLAY 0.617021 (-1940 4160);
PAINT ORANGE (-1940 4160);
FORCEPROP 2 LASTPIN (-1950 4100) $PN 126
J 0
(-1940 4110);
DISPLAY 0.617021 (-1940 4110);
PAINT ORANGE (-1940 4110);
FORCEPROP 2 LASTPIN (-1950 4050) $PN 264
J 0
(-1940 4060);
DISPLAY 0.617021 (-1940 4060);
PAINT ORANGE (-1940 4060);
FORCEPROP 2 LASTPIN (-1950 4000) $PN 119
J 0
(-1940 4010);
DISPLAY 0.617021 (-1940 4010);
PAINT ORANGE (-1940 4010);
FORCEPROP 2 LASTPIN (-1950 3950) $PN 258
J 0
(-1940 3960);
DISPLAY 0.617021 (-1940 3960);
PAINT ORANGE (-1940 3960);
FORCEPROP 2 LASTPIN (-1950 3900) $PN 113
J 0
(-1940 3910);
DISPLAY 0.617021 (-1940 3910);
PAINT ORANGE (-1940 3910);
FORCEPROP 2 LASTPIN (-1950 3850) $PN 251
J 0
(-1940 3860);
DISPLAY 0.617021 (-1940 3860);
PAINT ORANGE (-1940 3860);
FORCEPROP 2 LASTPIN (-1950 3800) $PN 106
J 0
(-1940 3810);
DISPLAY 0.617021 (-1940 3810);
PAINT ORANGE (-1940 3810);
FORCEPROP 2 LASTPIN (-1950 3750) $PN 260
J 0
(-1940 3760);
DISPLAY 0.617021 (-1940 3760);
PAINT ORANGE (-1940 3760);
FORCEPROP 2 LASTPIN (-1950 3700) $PN 115
J 0
(-1940 3710);
DISPLAY 0.617021 (-1940 3710);
PAINT ORANGE (-1940 3710);
FORCEPROP 2 LASTPIN (-1950 3650) $PN 253
J 0
(-1940 3660);
DISPLAY 0.617021 (-1940 3660);
PAINT ORANGE (-1940 3660);
FORCEPROP 2 LASTPIN (-1950 3600) $PN 108
J 0
(-1940 3610);
DISPLAY 0.617021 (-1940 3610);
PAINT ORANGE (-1940 3610);
FORCEPROP 2 LASTPIN (-1950 3550) $PN 247
J 0
(-1940 3560);
DISPLAY 0.617021 (-1940 3560);
PAINT ORANGE (-1940 3560);
FORCEPROP 2 LASTPIN (-1950 3500) $PN 102
J 0
(-1940 3510);
DISPLAY 0.617021 (-1940 3510);
PAINT ORANGE (-1940 3510);
FORCEPROP 2 LASTPIN (-1950 3450) $PN 240
J 0
(-1940 3460);
DISPLAY 0.617021 (-1940 3460);
PAINT ORANGE (-1940 3460);
FORCEPROP 2 LASTPIN (-1950 3400) $PN 95
J 0
(-1940 3410);
DISPLAY 0.617021 (-1940 3410);
PAINT ORANGE (-1940 3410);
FORCEPROP 2 LASTPIN (-1950 3350) $PN 249
J 0
(-1940 3360);
DISPLAY 0.617021 (-1940 3360);
PAINT ORANGE (-1940 3360);
FORCEPROP 2 LASTPIN (-1950 3300) $PN 104
J 0
(-1940 3310);
DISPLAY 0.617021 (-1940 3310);
PAINT ORANGE (-1940 3310);
FORCEPROP 2 LASTPIN (-1950 3250) $PN 242
J 0
(-1940 3260);
DISPLAY 0.617021 (-1940 3260);
PAINT ORANGE (-1940 3260);
FORCEPROP 2 LASTPIN (-1950 3200) $PN 97
J 0
(-1940 3210);
DISPLAY 0.617021 (-1940 3210);
PAINT ORANGE (-1940 3210);
FORCEPROP 2 LASTPIN (-1950 3150) $PN 188
J 0
(-1940 3160);
DISPLAY 0.617021 (-1940 3160);
PAINT ORANGE (-1940 3160);
FORCEPROP 2 LASTPIN (-1950 3100) $PN 43
J 0
(-1940 3110);
DISPLAY 0.617021 (-1940 3110);
PAINT ORANGE (-1940 3110);
FORCEPROP 2 LASTPIN (-1950 3050) $PN 181
J 0
(-1940 3060);
DISPLAY 0.617021 (-1940 3060);
PAINT ORANGE (-1940 3060);
FORCEPROP 2 LASTPIN (-1950 3000) $PN 36
J 0
(-1940 3010);
DISPLAY 0.617021 (-1940 3010);
PAINT ORANGE (-1940 3010);
FORCEPROP 2 LASTPIN (-1950 2950) $PN 190
J 0
(-1940 2960);
DISPLAY 0.617021 (-1940 2960);
PAINT ORANGE (-1940 2960);
FORCEPROP 2 LASTPIN (-1950 2900) $PN 45
J 0
(-1940 2910);
DISPLAY 0.617021 (-1940 2910);
PAINT ORANGE (-1940 2910);
FORCEPROP 2 LASTPIN (-1950 2850) $PN 183
J 0
(-1940 2860);
DISPLAY 0.617021 (-1940 2860);
PAINT ORANGE (-1940 2860);
FORCEPROP 2 LASTPIN (-1950 2800) $PN 38
J 0
(-1940 2810);
DISPLAY 0.617021 (-1940 2810);
PAINT ORANGE (-1940 2810);
FORCEPROP 2 LASTPIN (-1950 2750) $PN 177
J 0
(-1940 2760);
DISPLAY 0.617021 (-1940 2760);
PAINT ORANGE (-1940 2760);
FORCEPROP 2 LASTPIN (-1950 2700) $PN 32
J 0
(-1940 2710);
DISPLAY 0.617021 (-1940 2710);
PAINT ORANGE (-1940 2710);
FORCEPROP 2 LASTPIN (-1950 2650) $PN 170
J 0
(-1940 2660);
DISPLAY 0.617021 (-1940 2660);
PAINT ORANGE (-1940 2660);
FORCEPROP 2 LASTPIN (-1950 2600) $PN 25
J 0
(-1940 2610);
DISPLAY 0.617021 (-1940 2610);
PAINT ORANGE (-1940 2610);
FORCEPROP 2 LASTPIN (-1950 2550) $PN 179
J 0
(-1940 2560);
DISPLAY 0.617021 (-1940 2560);
PAINT ORANGE (-1940 2560);
FORCEPROP 2 LASTPIN (-1950 2500) $PN 34
J 0
(-1940 2510);
DISPLAY 0.617021 (-1940 2510);
PAINT ORANGE (-1940 2510);
FORCEPROP 2 LASTPIN (-1950 2450) $PN 172
J 0
(-1940 2460);
DISPLAY 0.617021 (-1940 2460);
PAINT ORANGE (-1940 2460);
FORCEPROP 2 LASTPIN (-1950 2400) $PN 27
J 0
(-1940 2410);
DISPLAY 0.617021 (-1940 2410);
PAINT ORANGE (-1940 2410);
FORCEPROP 2 LASTPIN (-1950 2350) $PN 166
J 0
(-1940 2360);
DISPLAY 0.617021 (-1940 2360);
PAINT ORANGE (-1940 2360);
FORCEPROP 2 LASTPIN (-1950 2300) $PN 21
J 0
(-1940 2310);
DISPLAY 0.617021 (-1940 2310);
PAINT ORANGE (-1940 2310);
FORCEPROP 2 LASTPIN (-1950 2250) $PN 159
J 0
(-1940 2260);
DISPLAY 0.617021 (-1940 2260);
PAINT ORANGE (-1940 2260);
FORCEPROP 2 LASTPIN (-1950 2200) $PN 14
J 0
(-1940 2210);
DISPLAY 0.617021 (-1940 2210);
PAINT ORANGE (-1940 2210);
FORCEPROP 2 LASTPIN (-1950 2150) $PN 168
J 0
(-1940 2160);
DISPLAY 0.617021 (-1940 2160);
PAINT ORANGE (-1940 2160);
FORCEPROP 2 LASTPIN (-1950 2100) $PN 23
J 0
(-1940 2110);
DISPLAY 0.617021 (-1940 2110);
PAINT ORANGE (-1940 2110);
FORCEPROP 2 LASTPIN (-1950 2050) $PN 161
J 0
(-1940 2060);
DISPLAY 0.617021 (-1940 2060);
PAINT ORANGE (-1940 2060);
FORCEPROP 2 LASTPIN (-1950 2000) $PN 16
J 0
(-1940 2010);
DISPLAY 0.617021 (-1940 2010);
PAINT ORANGE (-1940 2010);
FORCEPROP 2 LASTPIN (-1950 1950) $PN 155
J 0
(-1940 1960);
DISPLAY 0.617021 (-1940 1960);
PAINT ORANGE (-1940 1960);
FORCEPROP 2 LASTPIN (-1950 1900) $PN 10
J 0
(-1940 1910);
DISPLAY 0.617021 (-1940 1910);
PAINT ORANGE (-1940 1910);
FORCEPROP 2 LASTPIN (-1950 1850) $PN 148
J 0
(-1940 1860);
DISPLAY 0.617021 (-1940 1860);
PAINT ORANGE (-1940 1860);
FORCEPROP 2 LASTPIN (-1950 1800) $PN 3
J 0
(-1940 1810);
DISPLAY 0.617021 (-1940 1810);
PAINT ORANGE (-1940 1810);
FORCEPROP 2 LASTPIN (-1950 1750) $PN 157
J 0
(-1940 1760);
DISPLAY 0.617021 (-1940 1760);
PAINT ORANGE (-1940 1760);
FORCEPROP 2 LASTPIN (-1950 1700) $PN 12
J 0
(-1940 1710);
DISPLAY 0.617021 (-1940 1710);
PAINT ORANGE (-1940 1710);
FORCEPROP 2 LASTPIN (-1950 1650) $PN 150
J 0
(-1940 1660);
DISPLAY 0.617021 (-1940 1660);
PAINT ORANGE (-1940 1660);
FORCEPROP 2 LASTPIN (-1950 1600) $PN 5
J 0
(-1940 1610);
DISPLAY 0.617021 (-1940 1610);
PAINT ORANGE (-1940 1610);
FORCEPROP 2 LASTPIN (-2950 3000) $PN 203
J 2
(-2960 3010);
DISPLAY 0.617021 (-2960 3010);
PAINT ORANGE (-2960 3010);
FORCEPROP 2 LASTPIN (-2950 2950) $PN 60
J 2
(-2960 2960);
DISPLAY 0.617021 (-2960 2960);
PAINT ORANGE (-2960 2960);
FORCEPROP 2 LASTPIN (-2950 3550) $PN 218
J 2
(-2960 3560);
DISPLAY 0.617021 (-2960 3560);
PAINT ORANGE (-2960 3560);
FORCEPROP 2 LASTPIN (-2950 3500) $PN 219
J 2
(-2960 3510);
DISPLAY 0.617021 (-2960 3510);
PAINT ORANGE (-2960 3510);
FORCEPROP 2 LASTPIN (-2950 3450) $PN 74
J 2
(-2960 3460);
DISPLAY 0.617021 (-2960 3460);
PAINT ORANGE (-2960 3460);
FORCEPROP 2 LASTPIN (-2950 3400) $PN 75
J 2
(-2960 3410);
DISPLAY 0.617021 (-2960 3410);
PAINT ORANGE (-2960 3410);
FORCEPROP 2 LASTPIN (-2950 2700) $PN 199
J 2
(-2960 2710);
DISPLAY 0.617021 (-2960 2710);
PAINT ORANGE (-2960 2710);
FORCEPROP 2 LASTPIN (-2950 2650) $PN 54
J 2
(-2960 2660);
DISPLAY 0.617021 (-2960 2660);
PAINT ORANGE (-2960 2660);
FORCEPROP 2 LASTPIN (-2950 2600) $PN 192
J 2
(-2960 2610);
DISPLAY 0.617021 (-2960 2610);
PAINT ORANGE (-2960 2610);
FORCEPROP 2 LASTPIN (-2950 2550) $PN 47
J 2
(-2960 2560);
DISPLAY 0.617021 (-2960 2560);
PAINT ORANGE (-2960 2560);
FORCEPROP 2 LASTPIN (-2950 2500) $PN 201
J 2
(-2960 2510);
DISPLAY 0.617021 (-2960 2510);
PAINT ORANGE (-2960 2510);
FORCEPROP 2 LASTPIN (-2950 2450) $PN 56
J 2
(-2960 2460);
DISPLAY 0.617021 (-2960 2460);
PAINT ORANGE (-2960 2460);
FORCEPROP 2 LASTPIN (-2950 2400) $PN 194
J 2
(-2960 2410);
DISPLAY 0.617021 (-2960 2410);
PAINT ORANGE (-2960 2410);
FORCEPROP 2 LASTPIN (-2950 2350) $PN 49
J 2
(-2960 2360);
DISPLAY 0.617021 (-2960 2360);
PAINT ORANGE (-2960 2360);
FORCEPROP 2 LASTPIN (-2950 3300) $PN 235
J 2
(-2960 3310);
DISPLAY 0.617021 (-2960 3310);
PAINT ORANGE (-2960 3310);
FORCEPROP 2 LASTPIN (-2950 3700) $PN 207
J 2
(-2960 3710);
DISPLAY 0.617021 (-2960 3710);
PAINT ORANGE (-2960 3710);
FORCEPROP 2 LASTPIN (-2950 3650) $PN 63
J 2
(-2960 3660);
DISPLAY 0.617021 (-2960 3660);
PAINT ORANGE (-2960 3660);
FORCEPROP 2 LASTPIN (-2950 3800) $PN 224
J 2
(-2960 3810);
DISPLAY 0.617021 (-2960 3810);
PAINT ORANGE (-2960 3810);
FORCEPROP 2 LASTPIN (-2950 3750) $PN 81
J 2
(-2960 3760);
DISPLAY 0.617021 (-2960 3760);
PAINT ORANGE (-2960 3760);
FORCEPROP 2 LASTPIN (-2950 2100) $PN 208
J 2
(-2960 2110);
DISPLAY 0.617021 (-2960 2110);
PAINT ORANGE (-2960 2110);
FORCEPROP 2 LASTPIN (-2950 2050) $PN 62
J 2
(-2960 2060);
DISPLAY 0.617021 (-2960 2060);
PAINT ORANGE (-2960 2060);
FORCEPROP 2 LASTPIN (-2950 4750) $PN 234
J 2
(-2960 4760);
DISPLAY 0.617021 (-2960 4760);
PAINT ORANGE (-2960 4760);
FORCEPROP 2 LASTPIN (-2950 4700) $PN 82
J 2
(-2960 4710);
DISPLAY 0.617021 (-2960 4710);
PAINT ORANGE (-2960 4710);
FORCEPROP 2 LASTPIN (-2950 4650) $PN 86
J 2
(-2960 4660);
DISPLAY 0.617021 (-2960 4660);
PAINT ORANGE (-2960 4660);
FORCEPROP 2 LASTPIN (-2950 4600) $PN 228
J 2
(-2960 4610);
DISPLAY 0.617021 (-2960 4610);
PAINT ORANGE (-2960 4610);
FORCEPROP 2 LASTPIN (-2950 4550) $PN 232
J 2
(-2960 4560);
DISPLAY 0.617021 (-2960 4560);
PAINT ORANGE (-2960 4560);
FORCEPROP 2 LASTPIN (-2950 4500) $PN 65
J 2
(-2960 4510);
DISPLAY 0.617021 (-2960 4510);
PAINT ORANGE (-2960 4510);
FORCEPROP 2 LASTPIN (-2950 4450) $PN 210
J 2
(-2960 4460);
DISPLAY 0.617021 (-2960 4460);
PAINT ORANGE (-2960 4460);
FORCEPROP 2 LASTPIN (-2950 4400) $PN 225
J 2
(-2960 4410);
DISPLAY 0.617021 (-2960 4410);
PAINT ORANGE (-2960 4410);
FORCEPROP 2 LASTPIN (-2950 4350) $PN 66
J 2
(-2960 4360);
DISPLAY 0.617021 (-2960 4360);
PAINT ORANGE (-2960 4360);
FORCEPROP 2 LASTPIN (-2950 4300) $PN 68
J 2
(-2960 4310);
DISPLAY 0.617021 (-2960 4310);
PAINT ORANGE (-2960 4310);
FORCEPROP 2 LASTPIN (-2950 4250) $PN 211
J 2
(-2960 4260);
DISPLAY 0.617021 (-2960 4260);
PAINT ORANGE (-2960 4260);
FORCEPROP 2 LASTPIN (-2950 4200) $PN 69
J 2
(-2960 4210);
DISPLAY 0.617021 (-2960 4210);
PAINT ORANGE (-2960 4210);
FORCEPROP 2 LASTPIN (-2950 4150) $PN 213
J 2
(-2960 4160);
DISPLAY 0.617021 (-2960 4160);
PAINT ORANGE (-2960 4160);
FORCEPROP 2 LASTPIN (-2950 4100) $PN 214
J 2
(-2960 4110);
DISPLAY 0.617021 (-2960 4110);
PAINT ORANGE (-2960 4110);
FORCEPROP 2 LASTPIN (-2950 4050) $PN 71
J 2
(-2960 4060);
DISPLAY 0.617021 (-2960 4060);
PAINT ORANGE (-2960 4060);
FORCEPROP 2 LASTPIN (-2950 4000) $PN 216
J 2
(-2960 4010);
DISPLAY 0.617021 (-2960 4010);
PAINT ORANGE (-2960 4010);
FORCEPROP 2 LASTPIN (-2950 3950) $PN 72
J 2
(-2960 3960);
DISPLAY 0.617021 (-2960 3960);
PAINT ORANGE (-2960 3960);
FORCEPROP 2 LASTPIN (-2950 3900) $PN 79
J 2
(-2960 3910);
DISPLAY 0.617021 (-2960 3910);
PAINT ORANGE (-2960 3910);
FORCEPROP 1 LAST PACK_TYPE PIP
J 0
(-2900 5050);
PAINT SKYBLUE (-2900 5050);
DISPLAY INVISIBLE (-2900 5050);
FORCEPROP 2 LAST SEC_TYPE PIP
J 0
(-2900 5050);
DISPLAY 1.021277 (-2900 5050);
PAINT ORANGE (-2900 5050);
DISPLAY INVISIBLE (-2900 5050);
FORCEPROP 2 LAST CDS_LIB mstr_sconn
J 0
(-2450 3100);
PAINT ORANGE (-2450 3100);
DISPLAY INVISIBLE (-2450 3100);
FORCEPROP 2 LAST BOM_COST DDR4_CH_M
J 0
(-2450 3100);
PAINT ORANGE (-2450 3100);
DISPLAY INVISIBLE (-2450 3100);
FORCEPROP 2 LAST SEC 1
J 0
(-2900 5050);
DISPLAY 0.680851 (-2900 5050);
PAINT MONO (-2900 5050);
DISPLAY INVISIBLE (-2900 5050);
FORCEPROP 2 LAST CDS_LOCATION J9L1
J 0
(-2900 5000);
DISPLAY 0.617021 (-2900 5000);
PAINT AQUA (-2900 5000);
DISPLAY INVISIBLE (-2900 5000);
FORCEPROP 1 LAST PATH I111
J 0
(-2450 4950);
PAINT GREEN (-2450 4950);
DISPLAY INVISIBLE (-2450 4950);
FORCEPROP 2 LAST ROOM DDR4_CH_M
J 0
(-2450 3100);
PAINT ORANGE (-2450 3100);
DISPLAY INVISIBLE (-2450 3100);
FORCEADD TAP..6
(-3200 4700);
FORCEPROP 3 LASTPIN (-3150 4700) SIG_NAME M_M_MA<16>
J 0
(-3140 4710);
DISPLAY 0.659574 (-3140 4710);
PAINT MONO (-3140 4710);
DISPLAY INVISIBLE (-3140 4710);
FORCEPROP 1 LASTPIN (-3150 4700) BN 16
J 0
(-3200 4710);
DISPLAY 0.617021 (-3200 4710);
PAINT PINK (-3200 4710);
FORCEPROP 2 LAST CDS_LIB mstr_standard
J 2
(-3200 4700);
DISPLAY 0.787234 (-3200 4700);
PAINT MONO (-3200 4700);
DISPLAY INVISIBLE (-3200 4700);
FORCEPROP 1 LAST BODY_TYPE PLUMBING
J 0
(-3200 4650);
DISPLAY 1.234043 (-3200 4650);
PAINT GREEN (-3200 4650);
DISPLAY INVISIBLE (-3200 4650);
FORCEPROP 1 LAST HDL_TAP TRUE
J 0
(-2875 4575);
DISPLAY 1.234043 (-2875 4575);
PAINT GREEN (-2875 4575);
DISPLAY INVISIBLE (-2875 4575);
FORCEPROP 1 LAST PATH I112
J 0
(-3200 4700);
DISPLAY 0.936170 (-3200 4700);
PAINT GREEN (-3200 4700);
DISPLAY INVISIBLE (-3200 4700);
FORCEADD TAP..6
(-3200 4750);
FORCEPROP 3 LASTPIN (-3150 4750) SIG_NAME M_M_MA<17>
J 0
(-3140 4760);
DISPLAY 0.659574 (-3140 4760);
PAINT MONO (-3140 4760);
DISPLAY INVISIBLE (-3140 4760);
FORCEPROP 1 LASTPIN (-3150 4750) BN 17
J 0
(-3200 4760);
DISPLAY 0.617021 (-3200 4760);
PAINT PINK (-3200 4760);
FORCEPROP 2 LAST CDS_LIB mstr_standard
J 0
(-3200 4750);
DISPLAY 0.787234 (-3200 4750);
PAINT MONO (-3200 4750);
DISPLAY INVISIBLE (-3200 4750);
FORCEPROP 1 LAST BODY_TYPE PLUMBING
J 0
(-3200 4700);
DISPLAY 1.234043 (-3200 4700);
PAINT GREEN (-3200 4700);
DISPLAY INVISIBLE (-3200 4700);
FORCEPROP 1 LAST HDL_TAP TRUE
J 0
(-2875 4625);
DISPLAY 1.234043 (-2875 4625);
PAINT GREEN (-2875 4625);
DISPLAY INVISIBLE (-2875 4625);
FORCEPROP 1 LAST PATH I113
J 0
(-3200 4750);
DISPLAY 0.936170 (-3200 4750);
PAINT GREEN (-3200 4750);
DISPLAY INVISIBLE (-3200 4750);
FORCEADD TAP..6
(-3200 4650);
FORCEPROP 3 LASTPIN (-3150 4650) SIG_NAME M_M_MA<15>
J 0
(-3140 4660);
DISPLAY 0.659574 (-3140 4660);
PAINT MONO (-3140 4660);
DISPLAY INVISIBLE (-3140 4660);
FORCEPROP 1 LASTPIN (-3150 4650) BN 15
J 0
(-3200 4660);
DISPLAY 0.617021 (-3200 4660);
PAINT PINK (-3200 4660);
FORCEPROP 2 LAST CDS_LIB mstr_standard
J 2
(-3200 4650);
DISPLAY 0.787234 (-3200 4650);
PAINT MONO (-3200 4650);
DISPLAY INVISIBLE (-3200 4650);
FORCEPROP 1 LAST BODY_TYPE PLUMBING
J 0
(-3200 4600);
DISPLAY 1.234043 (-3200 4600);
PAINT GREEN (-3200 4600);
DISPLAY INVISIBLE (-3200 4600);
FORCEPROP 1 LAST HDL_TAP TRUE
J 0
(-2875 4525);
DISPLAY 1.234043 (-2875 4525);
PAINT GREEN (-2875 4525);
DISPLAY INVISIBLE (-2875 4525);
FORCEPROP 1 LAST PATH I114
J 0
(-3200 4650);
DISPLAY 0.936170 (-3200 4650);
PAINT GREEN (-3200 4650);
DISPLAY INVISIBLE (-3200 4650);
FORCEADD TAP..6
(-3200 4600);
FORCEPROP 3 LASTPIN (-3150 4600) SIG_NAME M_M_MA<14>
J 0
(-3140 4610);
DISPLAY 0.659574 (-3140 4610);
PAINT MONO (-3140 4610);
DISPLAY INVISIBLE (-3140 4610);
FORCEPROP 1 LASTPIN (-3150 4600) BN 14
J 0
(-3200 4610);
DISPLAY 0.617021 (-3200 4610);
PAINT PINK (-3200 4610);
FORCEPROP 2 LAST CDS_LIB mstr_standard
J 2
(-3200 4600);
DISPLAY 0.787234 (-3200 4600);
PAINT MONO (-3200 4600);
DISPLAY INVISIBLE (-3200 4600);
FORCEPROP 1 LAST BODY_TYPE PLUMBING
J 0
(-3200 4550);
DISPLAY 1.234043 (-3200 4550);
PAINT GREEN (-3200 4550);
DISPLAY INVISIBLE (-3200 4550);
FORCEPROP 1 LAST HDL_TAP TRUE
J 0
(-2875 4475);
DISPLAY 1.234043 (-2875 4475);
PAINT GREEN (-2875 4475);
DISPLAY INVISIBLE (-2875 4475);
FORCEPROP 1 LAST PATH I115
J 0
(-3200 4600);
DISPLAY 0.936170 (-3200 4600);
PAINT GREEN (-3200 4600);
DISPLAY INVISIBLE (-3200 4600);
FORCEADD TAP..6
(-3200 4550);
FORCEPROP 3 LASTPIN (-3150 4550) SIG_NAME M_M_MA<13>
J 0
(-3140 4560);
DISPLAY 0.659574 (-3140 4560);
PAINT MONO (-3140 4560);
DISPLAY INVISIBLE (-3140 4560);
FORCEPROP 1 LASTPIN (-3150 4550) BN 13
J 0
(-3200 4560);
DISPLAY 0.617021 (-3200 4560);
PAINT PINK (-3200 4560);
FORCEPROP 2 LAST CDS_LIB mstr_standard
J 2
(-3200 4550);
DISPLAY 0.787234 (-3200 4550);
PAINT MONO (-3200 4550);
DISPLAY INVISIBLE (-3200 4550);
FORCEPROP 1 LAST BODY_TYPE PLUMBING
J 0
(-3200 4500);
DISPLAY 1.234043 (-3200 4500);
PAINT GREEN (-3200 4500);
DISPLAY INVISIBLE (-3200 4500);
FORCEPROP 1 LAST HDL_TAP TRUE
J 0
(-2875 4425);
DISPLAY 1.234043 (-2875 4425);
PAINT GREEN (-2875 4425);
DISPLAY INVISIBLE (-2875 4425);
FORCEPROP 1 LAST PATH I116
J 0
(-3200 4550);
DISPLAY 0.936170 (-3200 4550);
PAINT GREEN (-3200 4550);
DISPLAY INVISIBLE (-3200 4550);
FORCEADD TAP..6
(-3200 4500);
FORCEPROP 3 LASTPIN (-3150 4500) SIG_NAME M_M_MA<12>
J 0
(-3140 4510);
DISPLAY 0.659574 (-3140 4510);
PAINT MONO (-3140 4510);
DISPLAY INVISIBLE (-3140 4510);
FORCEPROP 1 LASTPIN (-3150 4500) BN 12
J 0
(-3200 4510);
DISPLAY 0.617021 (-3200 4510);
PAINT PINK (-3200 4510);
FORCEPROP 2 LAST CDS_LIB mstr_standard
J 2
(-3200 4500);
DISPLAY 0.787234 (-3200 4500);
PAINT MONO (-3200 4500);
DISPLAY INVISIBLE (-3200 4500);
FORCEPROP 1 LAST BODY_TYPE PLUMBING
J 0
(-3200 4450);
DISPLAY 1.234043 (-3200 4450);
PAINT GREEN (-3200 4450);
DISPLAY INVISIBLE (-3200 4450);
FORCEPROP 1 LAST HDL_TAP TRUE
J 0
(-2875 4375);
DISPLAY 1.234043 (-2875 4375);
PAINT GREEN (-2875 4375);
DISPLAY INVISIBLE (-2875 4375);
FORCEPROP 1 LAST PATH I117
J 0
(-3200 4500);
DISPLAY 0.936170 (-3200 4500);
PAINT GREEN (-3200 4500);
DISPLAY INVISIBLE (-3200 4500);
FORCEADD TAP..6
(-3200 4450);
FORCEPROP 3 LASTPIN (-3150 4450) SIG_NAME M_M_MA<11>
J 0
(-3140 4460);
DISPLAY 0.659574 (-3140 4460);
PAINT MONO (-3140 4460);
DISPLAY INVISIBLE (-3140 4460);
FORCEPROP 1 LASTPIN (-3150 4450) BN 11
J 0
(-3200 4460);
DISPLAY 0.617021 (-3200 4460);
PAINT PINK (-3200 4460);
FORCEPROP 2 LAST CDS_LIB mstr_standard
J 2
(-3200 4450);
DISPLAY 0.787234 (-3200 4450);
PAINT MONO (-3200 4450);
DISPLAY INVISIBLE (-3200 4450);
FORCEPROP 1 LAST BODY_TYPE PLUMBING
J 0
(-3200 4400);
DISPLAY 1.234043 (-3200 4400);
PAINT GREEN (-3200 4400);
DISPLAY INVISIBLE (-3200 4400);
FORCEPROP 1 LAST HDL_TAP TRUE
J 0
(-2875 4325);
DISPLAY 1.234043 (-2875 4325);
PAINT GREEN (-2875 4325);
DISPLAY INVISIBLE (-2875 4325);
FORCEPROP 1 LAST PATH I118
J 0
(-3200 4450);
DISPLAY 0.936170 (-3200 4450);
PAINT GREEN (-3200 4450);
DISPLAY INVISIBLE (-3200 4450);
FORCEADD TAP..6
(-3200 4400);
FORCEPROP 3 LASTPIN (-3150 4400) SIG_NAME M_M_MA<10>
J 0
(-3140 4410);
DISPLAY 0.659574 (-3140 4410);
PAINT MONO (-3140 4410);
DISPLAY INVISIBLE (-3140 4410);
FORCEPROP 1 LASTPIN (-3150 4400) BN 10
J 0
(-3200 4410);
DISPLAY 0.617021 (-3200 4410);
PAINT PINK (-3200 4410);
FORCEPROP 2 LAST CDS_LIB mstr_standard
J 2
(-3200 4400);
DISPLAY 0.787234 (-3200 4400);
PAINT MONO (-3200 4400);
DISPLAY INVISIBLE (-3200 4400);
FORCEPROP 1 LAST BODY_TYPE PLUMBING
J 0
(-3200 4350);
DISPLAY 1.234043 (-3200 4350);
PAINT GREEN (-3200 4350);
DISPLAY INVISIBLE (-3200 4350);
FORCEPROP 1 LAST HDL_TAP TRUE
J 0
(-2875 4275);
DISPLAY 1.234043 (-2875 4275);
PAINT GREEN (-2875 4275);
DISPLAY INVISIBLE (-2875 4275);
FORCEPROP 1 LAST PATH I119
J 0
(-3200 4400);
DISPLAY 0.936170 (-3200 4400);
PAINT GREEN (-3200 4400);
DISPLAY INVISIBLE (-3200 4400);
FORCEADD TAP..6
R 2
(900 4500);
FORCEPROP 3 LASTPIN (850 4500) SIG_NAME M_M_DQS_DN<11>
J 0
(860 4510);
DISPLAY 0.659574 (860 4510);
PAINT MONO (860 4510);
DISPLAY INVISIBLE (860 4510);
FORCEPROP 1 LASTPIN (850 4500) BN 11
J 2
(900 4510);
DISPLAY 0.617021 (900 4510);
PAINT PINK (900 4510);
FORCEPROP 2 LAST CDS_LIB mstr_standard
J 0
(900 4500);
DISPLAY 0.787234 (900 4500);
PAINT MONO (900 4500);
DISPLAY INVISIBLE (900 4500);
FORCEPROP 1 LAST BODY_TYPE PLUMBING
J 2
(900 4450);
DISPLAY 1.234043 (900 4450);
PAINT GREEN (900 4450);
DISPLAY INVISIBLE (900 4450);
FORCEPROP 1 LAST HDL_TAP TRUE
J 2
(575 4375);
DISPLAY 1.234043 (575 4375);
PAINT GREEN (575 4375);
DISPLAY INVISIBLE (575 4375);
FORCEPROP 1 LAST PATH I12
J 2
(900 4500);
DISPLAY 0.936170 (900 4500);
PAINT GREEN (900 4500);
DISPLAY INVISIBLE (900 4500);
FORCEADD TAP..6
(-3200 4300);
FORCEPROP 3 LASTPIN (-3150 4300) SIG_NAME M_M_MA<8>
J 0
(-3140 4310);
DISPLAY 0.659574 (-3140 4310);
PAINT MONO (-3140 4310);
DISPLAY INVISIBLE (-3140 4310);
FORCEPROP 1 LASTPIN (-3150 4300) BN 8
J 0
(-3200 4310);
DISPLAY 0.617021 (-3200 4310);
PAINT PINK (-3200 4310);
FORCEPROP 2 LAST CDS_LIB mstr_standard
J 2
(-3200 4300);
DISPLAY 0.787234 (-3200 4300);
PAINT MONO (-3200 4300);
DISPLAY INVISIBLE (-3200 4300);
FORCEPROP 1 LAST BODY_TYPE PLUMBING
J 0
(-3200 4250);
DISPLAY 1.234043 (-3200 4250);
PAINT GREEN (-3200 4250);
DISPLAY INVISIBLE (-3200 4250);
FORCEPROP 1 LAST HDL_TAP TRUE
J 0
(-2875 4175);
DISPLAY 1.234043 (-2875 4175);
PAINT GREEN (-2875 4175);
DISPLAY INVISIBLE (-2875 4175);
FORCEPROP 1 LAST PATH I120
J 0
(-3200 4300);
DISPLAY 0.936170 (-3200 4300);
PAINT GREEN (-3200 4300);
DISPLAY INVISIBLE (-3200 4300);
FORCEADD TAP..6
(-3200 4350);
FORCEPROP 3 LASTPIN (-3150 4350) SIG_NAME M_M_MA<9>
J 0
(-3140 4360);
DISPLAY 0.659574 (-3140 4360);
PAINT MONO (-3140 4360);
DISPLAY INVISIBLE (-3140 4360);
FORCEPROP 1 LASTPIN (-3150 4350) BN 9
J 0
(-3200 4360);
DISPLAY 0.617021 (-3200 4360);
PAINT PINK (-3200 4360);
FORCEPROP 2 LAST CDS_LIB mstr_standard
J 2
(-3200 4350);
DISPLAY 0.787234 (-3200 4350);
PAINT MONO (-3200 4350);
DISPLAY INVISIBLE (-3200 4350);
FORCEPROP 1 LAST BODY_TYPE PLUMBING
J 0
(-3200 4300);
DISPLAY 1.234043 (-3200 4300);
PAINT GREEN (-3200 4300);
DISPLAY INVISIBLE (-3200 4300);
FORCEPROP 1 LAST HDL_TAP TRUE
J 0
(-2875 4225);
DISPLAY 1.234043 (-2875 4225);
PAINT GREEN (-2875 4225);
DISPLAY INVISIBLE (-2875 4225);
FORCEPROP 1 LAST PATH I121
J 0
(-3200 4350);
DISPLAY 0.936170 (-3200 4350);
PAINT GREEN (-3200 4350);
DISPLAY INVISIBLE (-3200 4350);
FORCEADD TAP..6
(-3200 4250);
FORCEPROP 3 LASTPIN (-3150 4250) SIG_NAME M_M_MA<7>
J 0
(-3140 4260);
DISPLAY 0.659574 (-3140 4260);
PAINT MONO (-3140 4260);
DISPLAY INVISIBLE (-3140 4260);
FORCEPROP 1 LASTPIN (-3150 4250) BN 7
J 0
(-3200 4260);
DISPLAY 0.617021 (-3200 4260);
PAINT PINK (-3200 4260);
FORCEPROP 2 LAST CDS_LIB mstr_standard
J 2
(-3200 4250);
DISPLAY 0.787234 (-3200 4250);
PAINT MONO (-3200 4250);
DISPLAY INVISIBLE (-3200 4250);
FORCEPROP 1 LAST BODY_TYPE PLUMBING
J 0
(-3200 4200);
DISPLAY 1.234043 (-3200 4200);
PAINT GREEN (-3200 4200);
DISPLAY INVISIBLE (-3200 4200);
FORCEPROP 1 LAST HDL_TAP TRUE
J 0
(-2875 4125);
DISPLAY 1.234043 (-2875 4125);
PAINT GREEN (-2875 4125);
DISPLAY INVISIBLE (-2875 4125);
FORCEPROP 1 LAST PATH I122
J 0
(-3200 4250);
DISPLAY 0.936170 (-3200 4250);
PAINT GREEN (-3200 4250);
DISPLAY INVISIBLE (-3200 4250);
FORCEADD TAP..6
(-3200 4200);
FORCEPROP 3 LASTPIN (-3150 4200) SIG_NAME M_M_MA<6>
J 0
(-3140 4210);
DISPLAY 0.659574 (-3140 4210);
PAINT MONO (-3140 4210);
DISPLAY INVISIBLE (-3140 4210);
FORCEPROP 1 LASTPIN (-3150 4200) BN 6
J 0
(-3200 4210);
DISPLAY 0.617021 (-3200 4210);
PAINT PINK (-3200 4210);
FORCEPROP 2 LAST CDS_LIB mstr_standard
J 2
(-3200 4200);
DISPLAY 0.787234 (-3200 4200);
PAINT MONO (-3200 4200);
DISPLAY INVISIBLE (-3200 4200);
FORCEPROP 1 LAST BODY_TYPE PLUMBING
J 0
(-3200 4150);
DISPLAY 1.234043 (-3200 4150);
PAINT GREEN (-3200 4150);
DISPLAY INVISIBLE (-3200 4150);
FORCEPROP 1 LAST HDL_TAP TRUE
J 0
(-2875 4075);
DISPLAY 1.234043 (-2875 4075);
PAINT GREEN (-2875 4075);
DISPLAY INVISIBLE (-2875 4075);
FORCEPROP 1 LAST PATH I123
J 0
(-3200 4200);
DISPLAY 0.936170 (-3200 4200);
PAINT GREEN (-3200 4200);
DISPLAY INVISIBLE (-3200 4200);
FORCEADD TAP..6
(-3200 4150);
FORCEPROP 3 LASTPIN (-3150 4150) SIG_NAME M_M_MA<5>
J 0
(-3140 4160);
DISPLAY 0.659574 (-3140 4160);
PAINT MONO (-3140 4160);
DISPLAY INVISIBLE (-3140 4160);
FORCEPROP 1 LASTPIN (-3150 4150) BN 5
J 0
(-3200 4160);
DISPLAY 0.617021 (-3200 4160);
PAINT PINK (-3200 4160);
FORCEPROP 2 LAST CDS_LIB mstr_standard
J 2
(-3200 4150);
DISPLAY 0.787234 (-3200 4150);
PAINT MONO (-3200 4150);
DISPLAY INVISIBLE (-3200 4150);
FORCEPROP 1 LAST BODY_TYPE PLUMBING
J 0
(-3200 4100);
DISPLAY 1.234043 (-3200 4100);
PAINT GREEN (-3200 4100);
DISPLAY INVISIBLE (-3200 4100);
FORCEPROP 1 LAST HDL_TAP TRUE
J 0
(-2875 4025);
DISPLAY 1.234043 (-2875 4025);
PAINT GREEN (-2875 4025);
DISPLAY INVISIBLE (-2875 4025);
FORCEPROP 1 LAST PATH I124
J 0
(-3200 4150);
DISPLAY 0.936170 (-3200 4150);
PAINT GREEN (-3200 4150);
DISPLAY INVISIBLE (-3200 4150);
FORCEADD TAP..6
(-3200 4100);
FORCEPROP 3 LASTPIN (-3150 4100) SIG_NAME M_M_MA<4>
J 0
(-3140 4110);
DISPLAY 0.659574 (-3140 4110);
PAINT MONO (-3140 4110);
DISPLAY INVISIBLE (-3140 4110);
FORCEPROP 1 LASTPIN (-3150 4100) BN 4
J 0
(-3200 4110);
DISPLAY 0.617021 (-3200 4110);
PAINT PINK (-3200 4110);
FORCEPROP 2 LAST CDS_LIB mstr_standard
J 2
(-3200 4100);
DISPLAY 0.787234 (-3200 4100);
PAINT MONO (-3200 4100);
DISPLAY INVISIBLE (-3200 4100);
FORCEPROP 1 LAST BODY_TYPE PLUMBING
J 0
(-3200 4050);
DISPLAY 1.234043 (-3200 4050);
PAINT GREEN (-3200 4050);
DISPLAY INVISIBLE (-3200 4050);
FORCEPROP 1 LAST HDL_TAP TRUE
J 0
(-2875 3975);
DISPLAY 1.234043 (-2875 3975);
PAINT GREEN (-2875 3975);
DISPLAY INVISIBLE (-2875 3975);
FORCEPROP 1 LAST PATH I125
J 0
(-3200 4100);
DISPLAY 0.936170 (-3200 4100);
PAINT GREEN (-3200 4100);
DISPLAY INVISIBLE (-3200 4100);
FORCEADD TAP..6
(-3200 4050);
FORCEPROP 3 LASTPIN (-3150 4050) SIG_NAME M_M_MA<3>
J 0
(-3140 4060);
DISPLAY 0.659574 (-3140 4060);
PAINT MONO (-3140 4060);
DISPLAY INVISIBLE (-3140 4060);
FORCEPROP 1 LASTPIN (-3150 4050) BN 3
J 0
(-3200 4060);
DISPLAY 0.617021 (-3200 4060);
PAINT PINK (-3200 4060);
FORCEPROP 2 LAST CDS_LIB mstr_standard
J 2
(-3200 4050);
DISPLAY 0.787234 (-3200 4050);
PAINT MONO (-3200 4050);
DISPLAY INVISIBLE (-3200 4050);
FORCEPROP 1 LAST BODY_TYPE PLUMBING
J 0
(-3200 4000);
DISPLAY 1.234043 (-3200 4000);
PAINT GREEN (-3200 4000);
DISPLAY INVISIBLE (-3200 4000);
FORCEPROP 1 LAST HDL_TAP TRUE
J 0
(-2875 3925);
DISPLAY 1.234043 (-2875 3925);
PAINT GREEN (-2875 3925);
DISPLAY INVISIBLE (-2875 3925);
FORCEPROP 1 LAST PATH I126
J 0
(-3200 4050);
DISPLAY 0.936170 (-3200 4050);
PAINT GREEN (-3200 4050);
DISPLAY INVISIBLE (-3200 4050);
FORCEADD TAP..6
(-3200 4000);
FORCEPROP 3 LASTPIN (-3150 4000) SIG_NAME M_M_MA<2>
J 0
(-3140 4010);
DISPLAY 0.659574 (-3140 4010);
PAINT MONO (-3140 4010);
DISPLAY INVISIBLE (-3140 4010);
FORCEPROP 1 LASTPIN (-3150 4000) BN 2
J 0
(-3200 4010);
DISPLAY 0.617021 (-3200 4010);
PAINT PINK (-3200 4010);
FORCEPROP 2 LAST CDS_LIB mstr_standard
J 2
(-3200 4000);
DISPLAY 0.787234 (-3200 4000);
PAINT MONO (-3200 4000);
DISPLAY INVISIBLE (-3200 4000);
FORCEPROP 1 LAST BODY_TYPE PLUMBING
J 0
(-3200 3950);
DISPLAY 1.234043 (-3200 3950);
PAINT GREEN (-3200 3950);
DISPLAY INVISIBLE (-3200 3950);
FORCEPROP 1 LAST HDL_TAP TRUE
J 0
(-2875 3875);
DISPLAY 1.234043 (-2875 3875);
PAINT GREEN (-2875 3875);
DISPLAY INVISIBLE (-2875 3875);
FORCEPROP 1 LAST PATH I127
J 0
(-3200 4000);
DISPLAY 0.936170 (-3200 4000);
PAINT GREEN (-3200 4000);
DISPLAY INVISIBLE (-3200 4000);
FORCEADD TAP..6
(-3200 3950);
FORCEPROP 3 LASTPIN (-3150 3950) SIG_NAME M_M_MA<1>
J 0
(-3140 3960);
DISPLAY 0.659574 (-3140 3960);
PAINT MONO (-3140 3960);
DISPLAY INVISIBLE (-3140 3960);
FORCEPROP 1 LASTPIN (-3150 3950) BN 1
J 0
(-3200 3960);
DISPLAY 0.617021 (-3200 3960);
PAINT PINK (-3200 3960);
FORCEPROP 2 LAST CDS_LIB mstr_standard
J 2
(-3200 3950);
DISPLAY 0.787234 (-3200 3950);
PAINT MONO (-3200 3950);
DISPLAY INVISIBLE (-3200 3950);
FORCEPROP 1 LAST BODY_TYPE PLUMBING
J 0
(-3200 3900);
DISPLAY 1.234043 (-3200 3900);
PAINT GREEN (-3200 3900);
DISPLAY INVISIBLE (-3200 3900);
FORCEPROP 1 LAST HDL_TAP TRUE
J 0
(-2875 3825);
DISPLAY 1.234043 (-2875 3825);
PAINT GREEN (-2875 3825);
DISPLAY INVISIBLE (-2875 3825);
FORCEPROP 1 LAST PATH I128
J 0
(-3200 3950);
DISPLAY 0.936170 (-3200 3950);
PAINT GREEN (-3200 3950);
DISPLAY INVISIBLE (-3200 3950);
FORCEADD TAP..6
(-3200 3900);
FORCEPROP 3 LASTPIN (-3150 3900) SIG_NAME M_M_MA<0>
J 0
(-3140 3910);
DISPLAY 0.659574 (-3140 3910);
PAINT MONO (-3140 3910);
DISPLAY INVISIBLE (-3140 3910);
FORCEPROP 1 LASTPIN (-3150 3900) BN 0
J 0
(-3200 3910);
DISPLAY 0.617021 (-3200 3910);
PAINT PINK (-3200 3910);
FORCEPROP 2 LAST CDS_LIB mstr_standard
J 2
(-3200 3900);
DISPLAY 0.787234 (-3200 3900);
PAINT MONO (-3200 3900);
DISPLAY INVISIBLE (-3200 3900);
FORCEPROP 1 LAST BODY_TYPE PLUMBING
J 0
(-3200 3850);
DISPLAY 1.234043 (-3200 3850);
PAINT GREEN (-3200 3850);
DISPLAY INVISIBLE (-3200 3850);
FORCEPROP 1 LAST HDL_TAP TRUE
J 0
(-2875 3775);
DISPLAY 1.234043 (-2875 3775);
PAINT GREEN (-2875 3775);
DISPLAY INVISIBLE (-2875 3775);
FORCEPROP 1 LAST PATH I129
J 0
(-3200 3900);
DISPLAY 0.936170 (-3200 3900);
PAINT GREEN (-3200 3900);
DISPLAY INVISIBLE (-3200 3900);
FORCEADD TAP..6
R 2
(900 4400);
FORCEPROP 3 LASTPIN (850 4400) SIG_NAME M_M_DQS_DN<10>
J 0
(860 4410);
DISPLAY 0.659574 (860 4410);
PAINT MONO (860 4410);
DISPLAY INVISIBLE (860 4410);
FORCEPROP 1 LASTPIN (850 4400) BN 10
J 2
(900 4410);
DISPLAY 0.617021 (900 4410);
PAINT PINK (900 4410);
FORCEPROP 2 LAST CDS_LIB mstr_standard
J 0
(900 4400);
DISPLAY 0.787234 (900 4400);
PAINT MONO (900 4400);
DISPLAY INVISIBLE (900 4400);
FORCEPROP 1 LAST BODY_TYPE PLUMBING
J 2
(900 4350);
DISPLAY 1.234043 (900 4350);
PAINT GREEN (900 4350);
DISPLAY INVISIBLE (900 4350);
FORCEPROP 1 LAST HDL_TAP TRUE
J 2
(575 4275);
DISPLAY 1.234043 (575 4275);
PAINT GREEN (575 4275);
DISPLAY INVISIBLE (575 4275);
FORCEPROP 1 LAST PATH I13
J 2
(900 4400);
DISPLAY 0.936170 (900 4400);
PAINT GREEN (900 4400);
DISPLAY INVISIBLE (900 4400);
FORCEADD TAP..6
(-3200 3800);
FORCEPROP 3 LASTPIN (-3150 3800) SIG_NAME M_M_BA<1>
J 0
(-3140 3810);
DISPLAY 0.659574 (-3140 3810);
PAINT MONO (-3140 3810);
DISPLAY INVISIBLE (-3140 3810);
FORCEPROP 1 LASTPIN (-3150 3800) BN 1
J 0
(-3200 3810);
DISPLAY 0.617021 (-3200 3810);
PAINT PINK (-3200 3810);
FORCEPROP 2 LAST CDS_LIB mstr_standard
J 0
(-3200 3800);
DISPLAY 0.787234 (-3200 3800);
PAINT MONO (-3200 3800);
DISPLAY INVISIBLE (-3200 3800);
FORCEPROP 1 LAST BODY_TYPE PLUMBING
J 0
(-3200 3750);
DISPLAY 1.234043 (-3200 3750);
PAINT GREEN (-3200 3750);
DISPLAY INVISIBLE (-3200 3750);
FORCEPROP 1 LAST HDL_TAP TRUE
J 0
(-2875 3675);
DISPLAY 1.234043 (-2875 3675);
PAINT GREEN (-2875 3675);
DISPLAY INVISIBLE (-2875 3675);
FORCEPROP 1 LAST PATH I130
J 0
(-3200 3800);
DISPLAY 0.936170 (-3200 3800);
PAINT GREEN (-3200 3800);
DISPLAY INVISIBLE (-3200 3800);
FORCEADD OFFPAGE..1
(-3800 4800);
FORCEPROP 2 LAST $XR0 62 
J 0
(-4051 4800);
DISPLAY 0.638298 (-4051 4800);
PAINT MONO (-4051 4800);
FORCEPROP 2 LAST $XR1 87 
J 0
(-4141 4800);
DISPLAY 0.638298 (-4141 4800);
PAINT MONO (-4141 4800);
FORCEPROP 2 LAST CDS_LIB mstr_standard
J 0
(-3800 4800);
DISPLAY 0.787234 (-3800 4800);
PAINT MONO (-3800 4800);
DISPLAY INVISIBLE (-3800 4800);
FORCEPROP 1 LAST OFFPAGE TRUE
J 0
(-3475 4675);
DISPLAY 0.936170 (-3475 4675);
PAINT GREEN (-3475 4675);
DISPLAY INVISIBLE (-3475 4675);
FORCEPROP 1 LAST COMMENT_BODY TRUE
J 0
(-3675 4700);
DISPLAY 0.936170 (-3675 4700);
PAINT GREEN (-3675 4700);
DISPLAY INVISIBLE (-3675 4700);
FORCEPROP 2 LAST PATH I131
J 0
(-3750 4875);
DISPLAY 0.787234 (-3750 4875);
PAINT MONO (-3750 4875);
DISPLAY INVISIBLE (-3750 4875);
FORCEADD OFFPAGE..1
(-3800 3850);
FORCEPROP 2 LAST $XR0 62 
J 0
(-4051 3850);
DISPLAY 0.638298 (-4051 3850);
PAINT MONO (-4051 3850);
FORCEPROP 2 LAST $XR1 87 
J 0
(-4141 3850);
DISPLAY 0.638298 (-4141 3850);
PAINT MONO (-4141 3850);
FORCEPROP 2 LAST CDS_LIB mstr_standard
J 0
(-3800 3850);
DISPLAY 0.787234 (-3800 3850);
PAINT MONO (-3800 3850);
DISPLAY INVISIBLE (-3800 3850);
FORCEPROP 1 LAST OFFPAGE TRUE
J 0
(-3475 3725);
DISPLAY 0.936170 (-3475 3725);
PAINT GREEN (-3475 3725);
DISPLAY INVISIBLE (-3475 3725);
FORCEPROP 1 LAST COMMENT_BODY TRUE
J 0
(-3675 3750);
DISPLAY 0.936170 (-3675 3750);
PAINT GREEN (-3675 3750);
DISPLAY INVISIBLE (-3675 3750);
FORCEPROP 2 LAST PATH I132
J 0
(-3750 3925);
DISPLAY 0.787234 (-3750 3925);
PAINT MONO (-3750 3925);
DISPLAY INVISIBLE (-3750 3925);
FORCEADD TAP..6
(-3200 3750);
FORCEPROP 3 LASTPIN (-3150 3750) SIG_NAME M_M_BA<0>
J 0
(-3140 3760);
DISPLAY 0.659574 (-3140 3760);
PAINT MONO (-3140 3760);
DISPLAY INVISIBLE (-3140 3760);
FORCEPROP 1 LASTPIN (-3150 3750) BN 0
J 0
(-3200 3760);
DISPLAY 0.617021 (-3200 3760);
PAINT PINK (-3200 3760);
FORCEPROP 2 LAST CDS_LIB mstr_standard
J 0
(-3200 3750);
DISPLAY 0.787234 (-3200 3750);
PAINT MONO (-3200 3750);
DISPLAY INVISIBLE (-3200 3750);
FORCEPROP 1 LAST BODY_TYPE PLUMBING
J 0
(-3200 3700);
DISPLAY 1.234043 (-3200 3700);
PAINT GREEN (-3200 3700);
DISPLAY INVISIBLE (-3200 3700);
FORCEPROP 1 LAST HDL_TAP TRUE
J 0
(-2875 3625);
DISPLAY 1.234043 (-2875 3625);
PAINT GREEN (-2875 3625);
DISPLAY INVISIBLE (-2875 3625);
FORCEPROP 1 LAST PATH I133
J 0
(-3200 3750);
DISPLAY 0.936170 (-3200 3750);
PAINT GREEN (-3200 3750);
DISPLAY INVISIBLE (-3200 3750);
FORCEADD TAP..6
(-3200 3650);
FORCEPROP 3 LASTPIN (-3150 3650) SIG_NAME M_M_BG<0>
J 0
(-3140 3660);
DISPLAY 0.659574 (-3140 3660);
PAINT MONO (-3140 3660);
DISPLAY INVISIBLE (-3140 3660);
FORCEPROP 1 LASTPIN (-3150 3650) BN 0
J 0
(-3200 3660);
DISPLAY 0.617021 (-3200 3660);
PAINT PINK (-3200 3660);
FORCEPROP 2 LAST CDS_LIB mstr_standard
J 0
(-3200 3650);
DISPLAY 0.787234 (-3200 3650);
PAINT MONO (-3200 3650);
DISPLAY INVISIBLE (-3200 3650);
FORCEPROP 1 LAST BODY_TYPE PLUMBING
J 0
(-3200 3600);
DISPLAY 1.234043 (-3200 3600);
PAINT GREEN (-3200 3600);
DISPLAY INVISIBLE (-3200 3600);
FORCEPROP 1 LAST HDL_TAP TRUE
J 0
(-2875 3525);
DISPLAY 1.234043 (-2875 3525);
PAINT GREEN (-2875 3525);
DISPLAY INVISIBLE (-2875 3525);
FORCEPROP 1 LAST PATH I134
J 0
(-3200 3650);
DISPLAY 0.936170 (-3200 3650);
PAINT GREEN (-3200 3650);
DISPLAY INVISIBLE (-3200 3650);
FORCEADD TAP..6
(-3200 3700);
FORCEPROP 3 LASTPIN (-3150 3700) SIG_NAME M_M_BG<1>
J 0
(-3140 3710);
DISPLAY 0.659574 (-3140 3710);
PAINT MONO (-3140 3710);
DISPLAY INVISIBLE (-3140 3710);
FORCEPROP 1 LASTPIN (-3150 3700) BN 1
J 0
(-3200 3710);
DISPLAY 0.617021 (-3200 3710);
PAINT PINK (-3200 3710);
FORCEPROP 2 LAST CDS_LIB mstr_standard
J 0
(-3200 3700);
DISPLAY 0.787234 (-3200 3700);
PAINT MONO (-3200 3700);
DISPLAY INVISIBLE (-3200 3700);
FORCEPROP 1 LAST BODY_TYPE PLUMBING
J 0
(-3200 3650);
DISPLAY 1.234043 (-3200 3650);
PAINT GREEN (-3200 3650);
DISPLAY INVISIBLE (-3200 3650);
FORCEPROP 1 LAST HDL_TAP TRUE
J 0
(-2875 3575);
DISPLAY 1.234043 (-2875 3575);
PAINT GREEN (-2875 3575);
DISPLAY INVISIBLE (-2875 3575);
FORCEPROP 1 LAST PATH I135
J 0
(-3200 3700);
DISPLAY 0.936170 (-3200 3700);
PAINT GREEN (-3200 3700);
DISPLAY INVISIBLE (-3200 3700);
FORCEADD OFFPAGE..1
(-3800 3325);
FORCEPROP 2 LAST $XR0 62 
J 0
(-4051 3325);
DISPLAY 0.638298 (-4051 3325);
PAINT MONO (-4051 3325);
FORCEPROP 2 LAST $XR1 87 
J 0
(-4141 3325);
DISPLAY 0.638298 (-4141 3325);
PAINT MONO (-4141 3325);
FORCEPROP 2 LAST CDS_LIB mstr_standard
J 0
(-3800 3325);
DISPLAY 0.787234 (-3800 3325);
PAINT MONO (-3800 3325);
DISPLAY INVISIBLE (-3800 3325);
FORCEPROP 1 LAST OFFPAGE TRUE
J 0
(-3475 3200);
DISPLAY 0.936170 (-3475 3200);
PAINT GREEN (-3475 3200);
DISPLAY INVISIBLE (-3475 3200);
FORCEPROP 1 LAST COMMENT_BODY TRUE
J 0
(-3675 3225);
DISPLAY 0.936170 (-3675 3225);
PAINT GREEN (-3675 3225);
DISPLAY INVISIBLE (-3675 3225);
FORCEPROP 2 LAST PATH I136
J 0
(-3750 3400);
DISPLAY 0.787234 (-3750 3400);
PAINT MONO (-3750 3400);
DISPLAY INVISIBLE (-3750 3400);
FORCEADD OFFPAGE..1
(-3800 3750);
FORCEPROP 2 LAST $XR0 62 
J 0
(-4051 3750);
DISPLAY 0.638298 (-4051 3750);
PAINT MONO (-4051 3750);
FORCEPROP 2 LAST $XR1 87 
J 0
(-4141 3750);
DISPLAY 0.638298 (-4141 3750);
PAINT MONO (-4141 3750);
FORCEPROP 2 LAST CDS_LIB mstr_standard
J 0
(-3800 3750);
DISPLAY 0.787234 (-3800 3750);
PAINT MONO (-3800 3750);
DISPLAY INVISIBLE (-3800 3750);
FORCEPROP 1 LAST OFFPAGE TRUE
J 0
(-3475 3625);
DISPLAY 0.936170 (-3475 3625);
PAINT GREEN (-3475 3625);
DISPLAY INVISIBLE (-3475 3625);
FORCEPROP 1 LAST COMMENT_BODY TRUE
J 0
(-3675 3650);
DISPLAY 0.936170 (-3675 3650);
PAINT GREEN (-3675 3650);
DISPLAY INVISIBLE (-3675 3650);
FORCEPROP 2 LAST PATH I137
J 0
(-3750 3825);
DISPLAY 0.787234 (-3750 3825);
PAINT MONO (-3750 3825);
DISPLAY INVISIBLE (-3750 3825);
FORCEADD TAP..6
(-3200 2650);
FORCEPROP 3 LASTPIN (-3150 2650) SIG_NAME M_M_ECC<6>
J 0
(-3140 2660);
DISPLAY 0.659574 (-3140 2660);
PAINT MONO (-3140 2660);
DISPLAY INVISIBLE (-3140 2660);
FORCEPROP 1 LASTPIN (-3150 2650) BN 6
J 0
(-3200 2660);
DISPLAY 0.617021 (-3200 2660);
PAINT PINK (-3200 2660);
FORCEPROP 2 LAST CDS_LIB mstr_standard
J 0
(-3200 2650);
DISPLAY 0.787234 (-3200 2650);
PAINT MONO (-3200 2650);
DISPLAY INVISIBLE (-3200 2650);
FORCEPROP 1 LAST BODY_TYPE PLUMBING
J 0
(-3200 2600);
DISPLAY 1.234043 (-3200 2600);
PAINT GREEN (-3200 2600);
DISPLAY INVISIBLE (-3200 2600);
FORCEPROP 1 LAST HDL_TAP TRUE
J 0
(-2875 2525);
DISPLAY 1.234043 (-2875 2525);
PAINT GREEN (-2875 2525);
DISPLAY INVISIBLE (-2875 2525);
FORCEPROP 1 LAST PATH I138
J 0
(-3200 2650);
DISPLAY 0.936170 (-3200 2650);
PAINT GREEN (-3200 2650);
DISPLAY INVISIBLE (-3200 2650);
FORCEADD TAP..6
(-3200 2700);
FORCEPROP 3 LASTPIN (-3150 2700) SIG_NAME M_M_ECC<7>
J 0
(-3140 2710);
DISPLAY 0.659574 (-3140 2710);
PAINT MONO (-3140 2710);
DISPLAY INVISIBLE (-3140 2710);
FORCEPROP 1 LASTPIN (-3150 2700) BN 7
J 0
(-3200 2710);
DISPLAY 0.617021 (-3200 2710);
PAINT PINK (-3200 2710);
FORCEPROP 2 LAST CDS_LIB mstr_standard
J 0
(-3200 2700);
DISPLAY 0.787234 (-3200 2700);
PAINT MONO (-3200 2700);
DISPLAY INVISIBLE (-3200 2700);
FORCEPROP 1 LAST BODY_TYPE PLUMBING
J 0
(-3200 2650);
DISPLAY 1.234043 (-3200 2650);
PAINT GREEN (-3200 2650);
DISPLAY INVISIBLE (-3200 2650);
FORCEPROP 1 LAST HDL_TAP TRUE
J 0
(-2875 2575);
DISPLAY 1.234043 (-2875 2575);
PAINT GREEN (-2875 2575);
DISPLAY INVISIBLE (-2875 2575);
FORCEPROP 1 LAST PATH I139
J 0
(-3200 2700);
DISPLAY 0.936170 (-3200 2700);
PAINT GREEN (-3200 2700);
DISPLAY INVISIBLE (-3200 2700);
FORCEADD TAP..6
R 2
(900 4300);
FORCEPROP 3 LASTPIN (850 4300) SIG_NAME M_M_DQS_DN<9>
J 0
(860 4310);
DISPLAY 0.659574 (860 4310);
PAINT MONO (860 4310);
DISPLAY INVISIBLE (860 4310);
FORCEPROP 1 LASTPIN (850 4300) BN 9
J 2
(900 4310);
DISPLAY 0.617021 (900 4310);
PAINT PINK (900 4310);
FORCEPROP 2 LAST CDS_LIB mstr_standard
J 0
(900 4300);
DISPLAY 0.787234 (900 4300);
PAINT MONO (900 4300);
DISPLAY INVISIBLE (900 4300);
FORCEPROP 1 LAST BODY_TYPE PLUMBING
J 2
(900 4250);
DISPLAY 1.234043 (900 4250);
PAINT GREEN (900 4250);
DISPLAY INVISIBLE (900 4250);
FORCEPROP 1 LAST HDL_TAP TRUE
J 2
(575 4175);
DISPLAY 1.234043 (575 4175);
PAINT GREEN (575 4175);
DISPLAY INVISIBLE (575 4175);
FORCEPROP 1 LAST PATH I14
J 2
(900 4300);
DISPLAY 0.936170 (900 4300);
PAINT GREEN (900 4300);
DISPLAY INVISIBLE (900 4300);
FORCEADD TAP..6
(-3200 2600);
FORCEPROP 3 LASTPIN (-3150 2600) SIG_NAME M_M_ECC<5>
J 0
(-3140 2610);
DISPLAY 0.659574 (-3140 2610);
PAINT MONO (-3140 2610);
DISPLAY INVISIBLE (-3140 2610);
FORCEPROP 1 LASTPIN (-3150 2600) BN 5
J 0
(-3200 2610);
DISPLAY 0.617021 (-3200 2610);
PAINT PINK (-3200 2610);
FORCEPROP 2 LAST CDS_LIB mstr_standard
J 0
(-3200 2600);
DISPLAY 0.787234 (-3200 2600);
PAINT MONO (-3200 2600);
DISPLAY INVISIBLE (-3200 2600);
FORCEPROP 1 LAST BODY_TYPE PLUMBING
J 0
(-3200 2550);
DISPLAY 1.234043 (-3200 2550);
PAINT GREEN (-3200 2550);
DISPLAY INVISIBLE (-3200 2550);
FORCEPROP 1 LAST HDL_TAP TRUE
J 0
(-2875 2475);
DISPLAY 1.234043 (-2875 2475);
PAINT GREEN (-2875 2475);
DISPLAY INVISIBLE (-2875 2475);
FORCEPROP 1 LAST PATH I140
J 0
(-3200 2600);
DISPLAY 0.936170 (-3200 2600);
PAINT GREEN (-3200 2600);
DISPLAY INVISIBLE (-3200 2600);
FORCEADD TAP..6
(-3200 2550);
FORCEPROP 3 LASTPIN (-3150 2550) SIG_NAME M_M_ECC<4>
J 0
(-3140 2560);
DISPLAY 0.659574 (-3140 2560);
PAINT MONO (-3140 2560);
DISPLAY INVISIBLE (-3140 2560);
FORCEPROP 1 LASTPIN (-3150 2550) BN 4
J 0
(-3200 2560);
DISPLAY 0.617021 (-3200 2560);
PAINT PINK (-3200 2560);
FORCEPROP 2 LAST CDS_LIB mstr_standard
J 0
(-3200 2550);
DISPLAY 0.787234 (-3200 2550);
PAINT MONO (-3200 2550);
DISPLAY INVISIBLE (-3200 2550);
FORCEPROP 1 LAST BODY_TYPE PLUMBING
J 0
(-3200 2500);
DISPLAY 1.234043 (-3200 2500);
PAINT GREEN (-3200 2500);
DISPLAY INVISIBLE (-3200 2500);
FORCEPROP 1 LAST HDL_TAP TRUE
J 0
(-2875 2425);
DISPLAY 1.234043 (-2875 2425);
PAINT GREEN (-2875 2425);
DISPLAY INVISIBLE (-2875 2425);
FORCEPROP 1 LAST PATH I141
J 0
(-3200 2550);
DISPLAY 0.936170 (-3200 2550);
PAINT GREEN (-3200 2550);
DISPLAY INVISIBLE (-3200 2550);
FORCEADD TAP..6
(-3200 2500);
FORCEPROP 3 LASTPIN (-3150 2500) SIG_NAME M_M_ECC<3>
J 0
(-3140 2510);
DISPLAY 0.659574 (-3140 2510);
PAINT MONO (-3140 2510);
DISPLAY INVISIBLE (-3140 2510);
FORCEPROP 1 LASTPIN (-3150 2500) BN 3
J 0
(-3200 2510);
DISPLAY 0.617021 (-3200 2510);
PAINT PINK (-3200 2510);
FORCEPROP 2 LAST CDS_LIB mstr_standard
J 0
(-3200 2500);
DISPLAY 0.787234 (-3200 2500);
PAINT MONO (-3200 2500);
DISPLAY INVISIBLE (-3200 2500);
FORCEPROP 1 LAST BODY_TYPE PLUMBING
J 0
(-3200 2450);
DISPLAY 1.234043 (-3200 2450);
PAINT GREEN (-3200 2450);
DISPLAY INVISIBLE (-3200 2450);
FORCEPROP 1 LAST HDL_TAP TRUE
J 0
(-2875 2375);
DISPLAY 1.234043 (-2875 2375);
PAINT GREEN (-2875 2375);
DISPLAY INVISIBLE (-2875 2375);
FORCEPROP 1 LAST PATH I142
J 0
(-3200 2500);
DISPLAY 0.936170 (-3200 2500);
PAINT GREEN (-3200 2500);
DISPLAY INVISIBLE (-3200 2500);
FORCEADD TAP..6
(-3200 2450);
FORCEPROP 3 LASTPIN (-3150 2450) SIG_NAME M_M_ECC<2>
J 0
(-3140 2460);
DISPLAY 0.659574 (-3140 2460);
PAINT MONO (-3140 2460);
DISPLAY INVISIBLE (-3140 2460);
FORCEPROP 1 LASTPIN (-3150 2450) BN 2
J 0
(-3200 2460);
DISPLAY 0.617021 (-3200 2460);
PAINT PINK (-3200 2460);
FORCEPROP 2 LAST CDS_LIB mstr_standard
J 0
(-3200 2450);
DISPLAY 0.787234 (-3200 2450);
PAINT MONO (-3200 2450);
DISPLAY INVISIBLE (-3200 2450);
FORCEPROP 1 LAST BODY_TYPE PLUMBING
J 0
(-3200 2400);
DISPLAY 1.234043 (-3200 2400);
PAINT GREEN (-3200 2400);
DISPLAY INVISIBLE (-3200 2400);
FORCEPROP 1 LAST HDL_TAP TRUE
J 0
(-2875 2325);
DISPLAY 1.234043 (-2875 2325);
PAINT GREEN (-2875 2325);
DISPLAY INVISIBLE (-2875 2325);
FORCEPROP 1 LAST PATH I143
J 0
(-3200 2450);
DISPLAY 0.936170 (-3200 2450);
PAINT GREEN (-3200 2450);
DISPLAY INVISIBLE (-3200 2450);
FORCEADD TAP..6
(-3200 2400);
FORCEPROP 3 LASTPIN (-3150 2400) SIG_NAME M_M_ECC<1>
J 0
(-3140 2410);
DISPLAY 0.659574 (-3140 2410);
PAINT MONO (-3140 2410);
DISPLAY INVISIBLE (-3140 2410);
FORCEPROP 1 LASTPIN (-3150 2400) BN 1
J 0
(-3200 2410);
DISPLAY 0.617021 (-3200 2410);
PAINT PINK (-3200 2410);
FORCEPROP 2 LAST CDS_LIB mstr_standard
J 0
(-3200 2400);
DISPLAY 0.787234 (-3200 2400);
PAINT MONO (-3200 2400);
DISPLAY INVISIBLE (-3200 2400);
FORCEPROP 1 LAST BODY_TYPE PLUMBING
J 0
(-3200 2350);
DISPLAY 1.234043 (-3200 2350);
PAINT GREEN (-3200 2350);
DISPLAY INVISIBLE (-3200 2350);
FORCEPROP 1 LAST HDL_TAP TRUE
J 0
(-2875 2275);
DISPLAY 1.234043 (-2875 2275);
PAINT GREEN (-2875 2275);
DISPLAY INVISIBLE (-2875 2275);
FORCEPROP 1 LAST PATH I144
J 0
(-3200 2400);
DISPLAY 0.936170 (-3200 2400);
PAINT GREEN (-3200 2400);
DISPLAY INVISIBLE (-3200 2400);
FORCEADD TAP..6
(-3200 2350);
FORCEPROP 3 LASTPIN (-3150 2350) SIG_NAME M_M_ECC<0>
J 0
(-3140 2360);
DISPLAY 0.659574 (-3140 2360);
PAINT MONO (-3140 2360);
DISPLAY INVISIBLE (-3140 2360);
FORCEPROP 1 LASTPIN (-3150 2350) BN 0
J 0
(-3200 2360);
DISPLAY 0.617021 (-3200 2360);
PAINT PINK (-3200 2360);
FORCEPROP 2 LAST CDS_LIB mstr_standard
J 0
(-3200 2350);
DISPLAY 0.787234 (-3200 2350);
PAINT MONO (-3200 2350);
DISPLAY INVISIBLE (-3200 2350);
FORCEPROP 1 LAST BODY_TYPE PLUMBING
J 0
(-3200 2300);
DISPLAY 1.234043 (-3200 2300);
PAINT GREEN (-3200 2300);
DISPLAY INVISIBLE (-3200 2300);
FORCEPROP 1 LAST HDL_TAP TRUE
J 0
(-2875 2225);
DISPLAY 1.234043 (-2875 2225);
PAINT GREEN (-2875 2225);
DISPLAY INVISIBLE (-2875 2225);
FORCEPROP 1 LAST PATH I145
J 0
(-3200 2350);
DISPLAY 0.936170 (-3200 2350);
PAINT GREEN (-3200 2350);
DISPLAY INVISIBLE (-3200 2350);
FORCEADD OFFPAGE..1
(-3800 2700);
FORCEPROP 2 LAST $XR0 62 
J 0
(-4051 2700);
DISPLAY 0.638298 (-4051 2700);
PAINT MONO (-4051 2700);
FORCEPROP 2 LAST $XR1 87 
J 0
(-4141 2700);
DISPLAY 0.638298 (-4141 2700);
PAINT MONO (-4141 2700);
FORCEPROP 2 LAST CDS_LIB mstr_standard
J 0
(-3800 2700);
DISPLAY 0.787234 (-3800 2700);
PAINT MONO (-3800 2700);
DISPLAY INVISIBLE (-3800 2700);
FORCEPROP 1 LAST OFFPAGE TRUE
J 0
(-3475 2575);
DISPLAY 0.936170 (-3475 2575);
PAINT GREEN (-3475 2575);
DISPLAY INVISIBLE (-3475 2575);
FORCEPROP 1 LAST COMMENT_BODY TRUE
J 0
(-3675 2600);
DISPLAY 0.936170 (-3675 2600);
PAINT GREEN (-3675 2600);
DISPLAY INVISIBLE (-3675 2600);
FORCEPROP 2 LAST PATH I146
J 0
(-3750 2775);
DISPLAY 0.787234 (-3750 2775);
PAINT MONO (-3750 2775);
DISPLAY INVISIBLE (-3750 2775);
FORCEADD OFFPAGE..1
(-3800 2650);
FORCEPROP 2 LAST $XR0 55 
J 0
(-4051 2650);
DISPLAY 0.638298 (-4051 2650);
PAINT MONO (-4051 2650);
FORCEPROP 2 LAST $XR1 83 
J 0
(-4141 2650);
DISPLAY 0.638298 (-4141 2650);
PAINT MONO (-4141 2650);
FORCEPROP 2 LAST $XR2 84 
J 0
(-4231 2650);
DISPLAY 0.638298 (-4231 2650);
PAINT MONO (-4231 2650);
FORCEPROP 2 LAST $XR3 85 
J 0
(-4321 2650);
DISPLAY 0.638298 (-4321 2650);
PAINT MONO (-4321 2650);
FORCEPROP 2 LAST $XR4 86 
J 0
(-4411 2650);
DISPLAY 0.638298 (-4411 2650);
PAINT MONO (-4411 2650);
FORCEPROP 2 LAST $XR5 87 
J 0
(-4501 2650);
DISPLAY 0.638298 (-4501 2650);
PAINT MONO (-4501 2650);
FORCEPROP 2 LAST CDS_LIB mstr_standard
J 0
(-3800 2650);
DISPLAY 0.787234 (-3800 2650);
PAINT MONO (-3800 2650);
DISPLAY INVISIBLE (-3800 2650);
FORCEPROP 1 LAST OFFPAGE TRUE
J 0
(-3475 2525);
DISPLAY 0.936170 (-3475 2525);
PAINT GREEN (-3475 2525);
DISPLAY INVISIBLE (-3475 2525);
FORCEPROP 1 LAST COMMENT_BODY TRUE
J 0
(-3675 2550);
DISPLAY 0.936170 (-3675 2550);
PAINT GREEN (-3675 2550);
DISPLAY INVISIBLE (-3675 2550);
FORCEPROP 2 LAST PATH I147
J 0
(-3750 2725);
DISPLAY 0.787234 (-3750 2725);
PAINT MONO (-3750 2725);
DISPLAY INVISIBLE (-3750 2725);
FORCEADD OFFPAGE..5
(-4025 2100);
FORCEPROP 2 LAST $XR0 87 
J 0
(-4249 2100);
DISPLAY 0.638298 (-4249 2100);
PAINT MONO (-4249 2100);
FORCEPROP 2 LAST $XR1 62 
J 0
(-4339 2100);
DISPLAY 0.638298 (-4339 2100);
PAINT MONO (-4339 2100);
FORCEPROP 2 LAST CDS_LIB mstr_standard
J 0
(-4025 2100);
DISPLAY 0.787234 (-4025 2100);
PAINT MONO (-4025 2100);
DISPLAY INVISIBLE (-4025 2100);
FORCEPROP 1 LAST OFFPAGE TRUE
J 0
(-3700 1975);
DISPLAY 1.404255 (-3700 1975);
PAINT GREEN (-3700 1975);
DISPLAY INVISIBLE (-3700 1975);
FORCEPROP 1 LAST COMMENT_BODY TRUE
J 0
(-3925 2025);
DISPLAY 1.404255 (-3925 2025);
PAINT GREEN (-3925 2025);
DISPLAY INVISIBLE (-3925 2025);
FORCEPROP 2 LAST PATH I148
J 0
(-3975 2175);
DISPLAY 0.787234 (-3975 2175);
PAINT MONO (-3975 2175);
DISPLAY INVISIBLE (-3975 2175);
FORCEADD OFFPAGE..1
(-4000 2050);
FORCEPROP 2 LAST $XR0 62 
J 0
(-4251 2050);
DISPLAY 0.638298 (-4251 2050);
PAINT MONO (-4251 2050);
FORCEPROP 2 LAST $XR1 87 
J 0
(-4341 2050);
DISPLAY 0.638298 (-4341 2050);
PAINT MONO (-4341 2050);
FORCEPROP 2 LAST CDS_LIB mstr_standard
J 0
(-4000 2050);
DISPLAY 0.787234 (-4000 2050);
PAINT MONO (-4000 2050);
DISPLAY INVISIBLE (-4000 2050);
FORCEPROP 1 LAST OFFPAGE TRUE
J 0
(-3675 1925);
DISPLAY 0.936170 (-3675 1925);
PAINT GREEN (-3675 1925);
DISPLAY INVISIBLE (-3675 1925);
FORCEPROP 1 LAST COMMENT_BODY TRUE
J 0
(-3875 1950);
DISPLAY 0.936170 (-3875 1950);
PAINT GREEN (-3875 1950);
DISPLAY INVISIBLE (-3875 1950);
FORCEPROP 2 LAST PATH I149
J 0
(-3950 2125);
DISPLAY 0.787234 (-3950 2125);
PAINT MONO (-3950 2125);
DISPLAY INVISIBLE (-3950 2125);
FORCEADD TAP..6
R 2
(900 4200);
FORCEPROP 3 LASTPIN (850 4200) SIG_NAME M_M_DQS_DN<8>
J 0
(860 4210);
DISPLAY 0.659574 (860 4210);
PAINT MONO (860 4210);
DISPLAY INVISIBLE (860 4210);
FORCEPROP 1 LASTPIN (850 4200) BN 8
J 2
(900 4210);
DISPLAY 0.617021 (900 4210);
PAINT PINK (900 4210);
FORCEPROP 2 LAST CDS_LIB mstr_standard
J 0
(900 4200);
DISPLAY 0.787234 (900 4200);
PAINT MONO (900 4200);
DISPLAY INVISIBLE (900 4200);
FORCEPROP 1 LAST BODY_TYPE PLUMBING
J 2
(900 4150);
DISPLAY 1.234043 (900 4150);
PAINT GREEN (900 4150);
DISPLAY INVISIBLE (900 4150);
FORCEPROP 1 LAST HDL_TAP TRUE
J 2
(575 4075);
DISPLAY 1.234043 (575 4075);
PAINT GREEN (575 4075);
DISPLAY INVISIBLE (575 4075);
FORCEPROP 1 LAST PATH I15
J 2
(900 4200);
DISPLAY 0.936170 (900 4200);
PAINT GREEN (900 4200);
DISPLAY INVISIBLE (900 4200);
FORCEADD OFFPAGE..6
(-3800 2750);
FORCEPROP 2 LAST $XR0 62 
J 0
(-4049 2750);
DISPLAY 0.638298 (-4049 2750);
PAINT MONO (-4049 2750);
FORCEPROP 2 LAST $XR1 87 
J 0
(-4139 2750);
DISPLAY 0.638298 (-4139 2750);
PAINT MONO (-4139 2750);
FORCEPROP 2 LAST CDS_LIB mstr_standard
J 0
(-3800 2750);
DISPLAY 0.787234 (-3800 2750);
PAINT MONO (-3800 2750);
DISPLAY INVISIBLE (-3800 2750);
FORCEPROP 1 LAST OFFPAGE TRUE
J 0
(-3475 2625);
DISPLAY 0.936170 (-3475 2625);
PAINT GREEN (-3475 2625);
DISPLAY INVISIBLE (-3475 2625);
FORCEPROP 1 LAST COMMENT_BODY TRUE
J 0
(-3700 2675);
DISPLAY 0.936170 (-3700 2675);
PAINT GREEN (-3700 2675);
DISPLAY INVISIBLE (-3700 2675);
FORCEPROP 2 LAST PATH I150
J 0
(-3750 2825);
DISPLAY 0.787234 (-3750 2825);
PAINT MONO (-3750 2825);
DISPLAY INVISIBLE (-3750 2825);
FORCEADD TAP..6
(-3650 3450);
FORCEPROP 3 LASTPIN (-3600 3450) SIG_NAME M_M_CLK_DP<2>
J 0
(-3590 3460);
DISPLAY 0.659574 (-3590 3460);
PAINT MONO (-3590 3460);
DISPLAY INVISIBLE (-3590 3460);
FORCEPROP 1 LASTPIN (-3600 3450) BN 2
J 0
(-3650 3460);
DISPLAY 0.617021 (-3650 3460);
PAINT PINK (-3650 3460);
FORCEPROP 2 LAST CDS_LIB mstr_standard
J 0
(-3650 3450);
DISPLAY 0.787234 (-3650 3450);
PAINT MONO (-3650 3450);
DISPLAY INVISIBLE (-3650 3450);
FORCEPROP 1 LAST BODY_TYPE PLUMBING
J 0
(-3650 3400);
DISPLAY 1.234043 (-3650 3400);
PAINT GREEN (-3650 3400);
DISPLAY INVISIBLE (-3650 3400);
FORCEPROP 1 LAST HDL_TAP TRUE
J 0
(-3325 3325);
DISPLAY 1.234043 (-3325 3325);
PAINT GREEN (-3325 3325);
DISPLAY INVISIBLE (-3325 3325);
FORCEPROP 1 LAST PATH I152
J 0
(-3650 3450);
DISPLAY 0.936170 (-3650 3450);
PAINT GREEN (-3650 3450);
DISPLAY INVISIBLE (-3650 3450);
FORCEADD TAP..6
(-3800 3400);
FORCEPROP 3 LASTPIN (-3750 3400) SIG_NAME M_M_CLK_DN<2>
J 0
(-3740 3410);
DISPLAY 0.659574 (-3740 3410);
PAINT MONO (-3740 3410);
DISPLAY INVISIBLE (-3740 3410);
FORCEPROP 1 LASTPIN (-3750 3400) BN 2
J 0
(-3800 3410);
DISPLAY 0.617021 (-3800 3410);
PAINT PINK (-3800 3410);
FORCEPROP 2 LAST CDS_LIB mstr_standard
J 0
(-3800 3400);
DISPLAY 0.787234 (-3800 3400);
PAINT MONO (-3800 3400);
DISPLAY INVISIBLE (-3800 3400);
FORCEPROP 1 LAST BODY_TYPE PLUMBING
J 0
(-3800 3350);
DISPLAY 1.234043 (-3800 3350);
PAINT GREEN (-3800 3350);
DISPLAY INVISIBLE (-3800 3350);
FORCEPROP 1 LAST HDL_TAP TRUE
J 0
(-3475 3275);
DISPLAY 1.234043 (-3475 3275);
PAINT GREEN (-3475 3275);
DISPLAY INVISIBLE (-3475 3275);
FORCEPROP 1 LAST PATH I153
J 0
(-3800 3400);
DISPLAY 0.936170 (-3800 3400);
PAINT GREEN (-3800 3400);
DISPLAY INVISIBLE (-3800 3400);
FORCEADD OFFPAGE..1
(-4400 3600);
FORCEPROP 2 LAST $XR0 62 
J 0
(-4651 3600);
DISPLAY 0.638298 (-4651 3600);
PAINT MONO (-4651 3600);
FORCEPROP 2 LAST $XR1 87 
J 0
(-4741 3600);
DISPLAY 0.638298 (-4741 3600);
PAINT MONO (-4741 3600);
FORCEPROP 2 LAST CDS_LIB mstr_standard
J 0
(-4400 3600);
DISPLAY 0.787234 (-4400 3600);
PAINT MONO (-4400 3600);
DISPLAY INVISIBLE (-4400 3600);
FORCEPROP 1 LAST OFFPAGE TRUE
J 0
(-4075 3475);
DISPLAY 0.936170 (-4075 3475);
PAINT GREEN (-4075 3475);
DISPLAY INVISIBLE (-4075 3475);
FORCEPROP 1 LAST COMMENT_BODY TRUE
J 0
(-4275 3500);
DISPLAY 0.936170 (-4275 3500);
PAINT GREEN (-4275 3500);
DISPLAY INVISIBLE (-4275 3500);
FORCEPROP 2 LAST PATH I155
J 0
(-4350 3675);
DISPLAY 0.787234 (-4350 3675);
PAINT MONO (-4350 3675);
DISPLAY INVISIBLE (-4350 3675);
FORCEADD OFFPAGE..1
(-4400 3650);
FORCEPROP 2 LAST $XR0 62 
J 0
(-4651 3650);
DISPLAY 0.638298 (-4651 3650);
PAINT MONO (-4651 3650);
FORCEPROP 2 LAST $XR1 87 
J 0
(-4741 3650);
DISPLAY 0.638298 (-4741 3650);
PAINT MONO (-4741 3650);
FORCEPROP 2 LAST CDS_LIB mstr_standard
J 0
(-4400 3650);
DISPLAY 0.787234 (-4400 3650);
PAINT MONO (-4400 3650);
DISPLAY INVISIBLE (-4400 3650);
FORCEPROP 1 LAST OFFPAGE TRUE
J 0
(-4075 3525);
DISPLAY 0.936170 (-4075 3525);
PAINT GREEN (-4075 3525);
DISPLAY INVISIBLE (-4075 3525);
FORCEPROP 1 LAST COMMENT_BODY TRUE
J 0
(-4275 3550);
DISPLAY 0.936170 (-4275 3550);
PAINT GREEN (-4275 3550);
DISPLAY INVISIBLE (-4275 3550);
FORCEPROP 2 LAST PATH I156
J 0
(-4350 3725);
DISPLAY 0.787234 (-4350 3725);
PAINT MONO (-4350 3725);
DISPLAY INVISIBLE (-4350 3725);
FORCEADD OFFPAGE..1
(-3800 3275);
FORCEPROP 2 LAST $XR0 62 
J 0
(-4051 3275);
DISPLAY 0.638298 (-4051 3275);
PAINT MONO (-4051 3275);
FORCEPROP 2 LAST $XR1 87 
J 0
(-4141 3275);
DISPLAY 0.638298 (-4141 3275);
PAINT MONO (-4141 3275);
FORCEPROP 2 LAST CDS_LIB mstr_standard
J 0
(-3800 3275);
DISPLAY 0.787234 (-3800 3275);
PAINT MONO (-3800 3275);
DISPLAY INVISIBLE (-3800 3275);
FORCEPROP 1 LAST OFFPAGE TRUE
J 0
(-3475 3150);
DISPLAY 0.936170 (-3475 3150);
PAINT GREEN (-3475 3150);
DISPLAY INVISIBLE (-3475 3150);
FORCEPROP 1 LAST COMMENT_BODY TRUE
J 0
(-3675 3175);
DISPLAY 0.936170 (-3675 3175);
PAINT GREEN (-3675 3175);
DISPLAY INVISIBLE (-3675 3175);
FORCEPROP 2 LAST PATH I157
J 0
(-3750 3350);
DISPLAY 0.787234 (-3750 3350);
PAINT MONO (-3750 3350);
DISPLAY INVISIBLE (-3750 3350);
FORCEADD OFFPAGE..1
(-3800 2900);
FORCEPROP 2 LAST $XR0 62 
J 0
(-4051 2900);
DISPLAY 0.638298 (-4051 2900);
PAINT MONO (-4051 2900);
FORCEPROP 2 LAST $XR1 87 
J 0
(-4141 2900);
DISPLAY 0.638298 (-4141 2900);
PAINT MONO (-4141 2900);
FORCEPROP 2 LAST CDS_LIB mstr_standard
J 0
(-3800 2900);
DISPLAY 0.787234 (-3800 2900);
PAINT MONO (-3800 2900);
DISPLAY INVISIBLE (-3800 2900);
FORCEPROP 1 LAST OFFPAGE TRUE
J 0
(-3475 2775);
DISPLAY 0.936170 (-3475 2775);
PAINT GREEN (-3475 2775);
DISPLAY INVISIBLE (-3475 2775);
FORCEPROP 1 LAST COMMENT_BODY TRUE
J 0
(-3675 2800);
DISPLAY 0.936170 (-3675 2800);
PAINT GREEN (-3675 2800);
DISPLAY INVISIBLE (-3675 2800);
FORCEPROP 2 LAST PATH I158
J 0
(-3750 2975);
DISPLAY 0.787234 (-3750 2975);
PAINT MONO (-3750 2975);
DISPLAY INVISIBLE (-3750 2975);
FORCEADD OFFPAGE..1
(-3800 3050);
FORCEPROP 2 LAST $XR0 62 
J 0
(-4051 3050);
DISPLAY 0.638298 (-4051 3050);
PAINT MONO (-4051 3050);
FORCEPROP 2 LAST $XR1 87 
J 0
(-4141 3050);
DISPLAY 0.638298 (-4141 3050);
PAINT MONO (-4141 3050);
FORCEPROP 2 LAST CDS_LIB mstr_standard
J 0
(-3800 3050);
DISPLAY 0.787234 (-3800 3050);
PAINT MONO (-3800 3050);
DISPLAY INVISIBLE (-3800 3050);
FORCEPROP 1 LAST OFFPAGE TRUE
J 0
(-3475 2925);
DISPLAY 0.936170 (-3475 2925);
PAINT GREEN (-3475 2925);
DISPLAY INVISIBLE (-3475 2925);
FORCEPROP 1 LAST COMMENT_BODY TRUE
J 0
(-3675 2950);
DISPLAY 0.936170 (-3675 2950);
PAINT GREEN (-3675 2950);
DISPLAY INVISIBLE (-3675 2950);
FORCEPROP 2 LAST PATH I159
J 0
(-3750 3125);
DISPLAY 0.787234 (-3750 3125);
PAINT MONO (-3750 3125);
DISPLAY INVISIBLE (-3750 3125);
FORCEADD TAP..6
R 2
(900 4100);
FORCEPROP 3 LASTPIN (850 4100) SIG_NAME M_M_DQS_DN<7>
J 0
(860 4110);
DISPLAY 0.659574 (860 4110);
PAINT MONO (860 4110);
DISPLAY INVISIBLE (860 4110);
FORCEPROP 1 LASTPIN (850 4100) BN 7
J 2
(900 4110);
DISPLAY 0.617021 (900 4110);
PAINT PINK (900 4110);
FORCEPROP 2 LAST CDS_LIB mstr_standard
J 0
(900 4100);
DISPLAY 0.787234 (900 4100);
PAINT MONO (900 4100);
DISPLAY INVISIBLE (900 4100);
FORCEPROP 1 LAST BODY_TYPE PLUMBING
J 2
(900 4050);
DISPLAY 1.234043 (900 4050);
PAINT GREEN (900 4050);
DISPLAY INVISIBLE (900 4050);
FORCEPROP 1 LAST HDL_TAP TRUE
J 2
(575 3975);
DISPLAY 1.234043 (575 3975);
PAINT GREEN (575 3975);
DISPLAY INVISIBLE (575 3975);
FORCEPROP 1 LAST PATH I16
J 2
(900 4100);
DISPLAY 0.936170 (900 4100);
PAINT GREEN (900 4100);
DISPLAY INVISIBLE (900 4100);
FORCEADD TAP..6
(-3200 3250);
FORCEPROP 3 LASTPIN (-3150 3250) SIG_NAME M_M_CS_N<7>
J 0
(-3140 3260);
DISPLAY 0.659574 (-3140 3260);
PAINT MONO (-3140 3260);
DISPLAY INVISIBLE (-3140 3260);
FORCEPROP 1 LASTPIN (-3150 3250) BN 7
J 0
(-3200 3260);
DISPLAY 0.617021 (-3200 3260);
PAINT PINK (-3200 3260);
FORCEPROP 2 LAST CDS_LIB mstr_standard
J 0
(-3200 3250);
DISPLAY 0.787234 (-3200 3250);
PAINT MONO (-3200 3250);
DISPLAY INVISIBLE (-3200 3250);
FORCEPROP 1 LAST BODY_TYPE PLUMBING
J 0
(-3200 3200);
DISPLAY 1.234043 (-3200 3200);
PAINT GREEN (-3200 3200);
DISPLAY INVISIBLE (-3200 3200);
FORCEPROP 1 LAST HDL_TAP TRUE
J 0
(-2875 3125);
DISPLAY 1.234043 (-2875 3125);
PAINT GREEN (-2875 3125);
DISPLAY INVISIBLE (-2875 3125);
FORCEPROP 1 LAST PATH I160
J 0
(-3200 3250);
DISPLAY 0.936170 (-3200 3250);
PAINT GREEN (-3200 3250);
DISPLAY INVISIBLE (-3200 3250);
FORCEADD TAP..6
(-3200 3200);
FORCEPROP 3 LASTPIN (-3150 3200) SIG_NAME M_M_CS_N<6>
J 0
(-3140 3210);
DISPLAY 0.659574 (-3140 3210);
PAINT MONO (-3140 3210);
DISPLAY INVISIBLE (-3140 3210);
FORCEPROP 1 LASTPIN (-3150 3200) BN 6
J 0
(-3200 3210);
DISPLAY 0.617021 (-3200 3210);
PAINT PINK (-3200 3210);
FORCEPROP 2 LAST CDS_LIB mstr_standard
J 0
(-3200 3200);
DISPLAY 0.787234 (-3200 3200);
PAINT MONO (-3200 3200);
DISPLAY INVISIBLE (-3200 3200);
FORCEPROP 1 LAST BODY_TYPE PLUMBING
J 0
(-3200 3150);
DISPLAY 1.234043 (-3200 3150);
PAINT GREEN (-3200 3150);
DISPLAY INVISIBLE (-3200 3150);
FORCEPROP 1 LAST HDL_TAP TRUE
J 0
(-2875 3075);
DISPLAY 1.234043 (-2875 3075);
PAINT GREEN (-2875 3075);
DISPLAY INVISIBLE (-2875 3075);
FORCEPROP 1 LAST PATH I161
J 0
(-3200 3200);
DISPLAY 0.936170 (-3200 3200);
PAINT GREEN (-3200 3200);
DISPLAY INVISIBLE (-3200 3200);
FORCEADD TAP..6
(-3200 3150);
FORCEPROP 3 LASTPIN (-3150 3150) SIG_NAME M_M_CS_N<5>
J 0
(-3140 3160);
DISPLAY 0.659574 (-3140 3160);
PAINT MONO (-3140 3160);
DISPLAY INVISIBLE (-3140 3160);
FORCEPROP 1 LASTPIN (-3150 3150) BN 5
J 0
(-3200 3160);
DISPLAY 0.617021 (-3200 3160);
PAINT PINK (-3200 3160);
FORCEPROP 2 LAST CDS_LIB mstr_standard
J 0
(-3200 3150);
DISPLAY 0.787234 (-3200 3150);
PAINT MONO (-3200 3150);
DISPLAY INVISIBLE (-3200 3150);
FORCEPROP 1 LAST BODY_TYPE PLUMBING
J 0
(-3200 3100);
DISPLAY 1.234043 (-3200 3100);
PAINT GREEN (-3200 3100);
DISPLAY INVISIBLE (-3200 3100);
FORCEPROP 1 LAST HDL_TAP TRUE
J 0
(-2875 3025);
DISPLAY 1.234043 (-2875 3025);
PAINT GREEN (-2875 3025);
DISPLAY INVISIBLE (-2875 3025);
FORCEPROP 1 LAST PATH I162
J 0
(-3200 3150);
DISPLAY 0.936170 (-3200 3150);
PAINT GREEN (-3200 3150);
DISPLAY INVISIBLE (-3200 3150);
FORCEADD TAP..6
(-3200 3100);
FORCEPROP 3 LASTPIN (-3150 3100) SIG_NAME M_M_CS_N<4>
J 0
(-3140 3110);
DISPLAY 0.659574 (-3140 3110);
PAINT MONO (-3140 3110);
DISPLAY INVISIBLE (-3140 3110);
FORCEPROP 1 LASTPIN (-3150 3100) BN 4
J 0
(-3200 3110);
DISPLAY 0.617021 (-3200 3110);
PAINT PINK (-3200 3110);
FORCEPROP 2 LAST CDS_LIB mstr_standard
J 0
(-3200 3100);
DISPLAY 0.787234 (-3200 3100);
PAINT MONO (-3200 3100);
DISPLAY INVISIBLE (-3200 3100);
FORCEPROP 1 LAST BODY_TYPE PLUMBING
J 0
(-3200 3050);
DISPLAY 1.234043 (-3200 3050);
PAINT GREEN (-3200 3050);
DISPLAY INVISIBLE (-3200 3050);
FORCEPROP 1 LAST HDL_TAP TRUE
J 0
(-2875 2975);
DISPLAY 1.234043 (-2875 2975);
PAINT GREEN (-2875 2975);
DISPLAY INVISIBLE (-2875 2975);
FORCEPROP 1 LAST PATH I163
J 0
(-3200 3100);
DISPLAY 0.936170 (-3200 3100);
PAINT GREEN (-3200 3100);
DISPLAY INVISIBLE (-3200 3100);
FORCEADD TAP..6
(-3200 3000);
FORCEPROP 3 LASTPIN (-3150 3000) SIG_NAME M_M_CKE<3>
J 0
(-3140 3010);
DISPLAY 0.659574 (-3140 3010);
PAINT MONO (-3140 3010);
DISPLAY INVISIBLE (-3140 3010);
FORCEPROP 1 LASTPIN (-3150 3000) BN 3
J 0
(-3200 3010);
DISPLAY 0.617021 (-3200 3010);
PAINT PINK (-3200 3010);
FORCEPROP 2 LAST CDS_LIB mstr_standard
J 0
(-3200 3000);
DISPLAY 0.787234 (-3200 3000);
PAINT MONO (-3200 3000);
DISPLAY INVISIBLE (-3200 3000);
FORCEPROP 1 LAST BODY_TYPE PLUMBING
J 0
(-3200 2950);
DISPLAY 1.234043 (-3200 2950);
PAINT GREEN (-3200 2950);
DISPLAY INVISIBLE (-3200 2950);
FORCEPROP 1 LAST HDL_TAP TRUE
J 0
(-2875 2875);
DISPLAY 1.234043 (-2875 2875);
PAINT GREEN (-2875 2875);
DISPLAY INVISIBLE (-2875 2875);
FORCEPROP 1 LAST PATH I164
J 0
(-3200 3000);
DISPLAY 0.936170 (-3200 3000);
PAINT GREEN (-3200 3000);
DISPLAY INVISIBLE (-3200 3000);
FORCEADD TAP..6
(-3200 2950);
FORCEPROP 3 LASTPIN (-3150 2950) SIG_NAME M_M_CKE<2>
J 0
(-3140 2960);
DISPLAY 0.659574 (-3140 2960);
PAINT MONO (-3140 2960);
DISPLAY INVISIBLE (-3140 2960);
FORCEPROP 1 LASTPIN (-3150 2950) BN 2
J 0
(-3200 2960);
DISPLAY 0.617021 (-3200 2960);
PAINT PINK (-3200 2960);
FORCEPROP 2 LAST CDS_LIB mstr_standard
J 0
(-3200 2950);
DISPLAY 0.787234 (-3200 2950);
PAINT MONO (-3200 2950);
DISPLAY INVISIBLE (-3200 2950);
FORCEPROP 1 LAST BODY_TYPE PLUMBING
J 0
(-3200 2900);
DISPLAY 1.234043 (-3200 2900);
PAINT GREEN (-3200 2900);
DISPLAY INVISIBLE (-3200 2900);
FORCEPROP 1 LAST HDL_TAP TRUE
J 0
(-2875 2825);
DISPLAY 1.234043 (-2875 2825);
PAINT GREEN (-2875 2825);
DISPLAY INVISIBLE (-2875 2825);
FORCEPROP 1 LAST PATH I165
J 0
(-3200 2950);
DISPLAY 0.936170 (-3200 2950);
PAINT GREEN (-3200 2950);
DISPLAY INVISIBLE (-3200 2950);
FORCEADD TAP..6
(-3200 2850);
FORCEPROP 3 LASTPIN (-3150 2850) SIG_NAME M_M_ODT<3>
J 0
(-3140 2860);
DISPLAY 0.659574 (-3140 2860);
PAINT MONO (-3140 2860);
DISPLAY INVISIBLE (-3140 2860);
FORCEPROP 1 LASTPIN (-3150 2850) BN 3
J 0
(-3200 2860);
DISPLAY 0.617021 (-3200 2860);
PAINT PINK (-3200 2860);
FORCEPROP 2 LAST CDS_LIB mstr_standard
J 0
(-3200 2850);
DISPLAY 0.787234 (-3200 2850);
PAINT MONO (-3200 2850);
DISPLAY INVISIBLE (-3200 2850);
FORCEPROP 1 LAST BODY_TYPE PLUMBING
J 0
(-3200 2800);
DISPLAY 1.234043 (-3200 2800);
PAINT GREEN (-3200 2800);
DISPLAY INVISIBLE (-3200 2800);
FORCEPROP 1 LAST HDL_TAP TRUE
J 0
(-2875 2725);
DISPLAY 1.234043 (-2875 2725);
PAINT GREEN (-2875 2725);
DISPLAY INVISIBLE (-2875 2725);
FORCEPROP 1 LAST PATH I166
J 0
(-3200 2850);
DISPLAY 0.936170 (-3200 2850);
PAINT GREEN (-3200 2850);
DISPLAY INVISIBLE (-3200 2850);
FORCEADD TAP..6
(-3200 2800);
FORCEPROP 3 LASTPIN (-3150 2800) SIG_NAME M_M_ODT<2>
J 0
(-3140 2810);
DISPLAY 0.659574 (-3140 2810);
PAINT MONO (-3140 2810);
DISPLAY INVISIBLE (-3140 2810);
FORCEPROP 1 LASTPIN (-3150 2800) BN 2
J 0
(-3200 2810);
DISPLAY 0.617021 (-3200 2810);
PAINT PINK (-3200 2810);
FORCEPROP 2 LAST CDS_LIB mstr_standard
J 0
(-3200 2800);
DISPLAY 0.787234 (-3200 2800);
PAINT MONO (-3200 2800);
DISPLAY INVISIBLE (-3200 2800);
FORCEPROP 1 LAST BODY_TYPE PLUMBING
J 0
(-3200 2750);
DISPLAY 1.234043 (-3200 2750);
PAINT GREEN (-3200 2750);
DISPLAY INVISIBLE (-3200 2750);
FORCEPROP 1 LAST HDL_TAP TRUE
J 0
(-2875 2675);
DISPLAY 1.234043 (-2875 2675);
PAINT GREEN (-2875 2675);
DISPLAY INVISIBLE (-2875 2675);
FORCEPROP 1 LAST PATH I167
J 0
(-3200 2800);
DISPLAY 0.936170 (-3200 2800);
PAINT GREEN (-3200 2800);
DISPLAY INVISIBLE (-3200 2800);
FORCEADD SCONN288_H44441003..4
(-300 2000);
FORCEPROP 1 LAST LOCATION J9L1
J 0
(-750 3100);
DISPLAY 0.617021 (-750 3100);
PAINT AQUA (-750 3100);
FORCEPROP 1 LAST PART_NUMBER H44441-003
J 0
(-750 950);
DISPLAY 0.617021 (-750 950);
PAINT BLUE (-750 950);
FORCEPROP 1 LAST MATERIAL SCONN
J 0
(-750 3050);
DISPLAY 0.617021 (-750 3050);
PAINT SKYBLUE (-750 3050);
FORCEPROP 2 LASTPIN (-800 2550) $PN 77
J 2
(-810 2560);
DISPLAY 0.617021 (-810 2560);
PAINT ORANGE (-810 2560);
FORCEPROP 2 LASTPIN (-800 2500) $PN 221
J 2
(-810 2510);
DISPLAY 0.617021 (-810 2510);
PAINT ORANGE (-810 2510);
FORCEPROP 2 LASTPIN (-800 2850) $PN 142
J 2
(-810 2860);
DISPLAY 0.617021 (-810 2860);
PAINT ORANGE (-810 2860);
FORCEPROP 2 LASTPIN (-800 2800) $PN 143
J 2
(-810 2810);
DISPLAY 0.617021 (-810 2810);
PAINT ORANGE (-810 2810);
FORCEPROP 2 LASTPIN (-800 2750) $PN 288
J 2
(-810 2760);
DISPLAY 0.617021 (-810 2760);
PAINT ORANGE (-810 2760);
FORCEPROP 2 LASTPIN (-800 2700) $PN 286
J 2
(-810 2710);
DISPLAY 0.617021 (-810 2710);
PAINT ORANGE (-810 2710);
FORCEPROP 2 LASTPIN (-800 2650) $PN 287
J 2
(-810 2660);
DISPLAY 0.617021 (-810 2660);
PAINT ORANGE (-810 2660);
FORCEPROP 2 LASTPIN (-800 2400) $PN 59
J 2
(-810 2410);
DISPLAY 0.617021 (-810 2410);
PAINT ORANGE (-810 2410);
FORCEPROP 2 LASTPIN (-800 2350) $PN 61
J 2
(-810 2360);
DISPLAY 0.617021 (-810 2360);
PAINT ORANGE (-810 2360);
FORCEPROP 2 LASTPIN (-800 2300) $PN 64
J 2
(-810 2310);
DISPLAY 0.617021 (-810 2310);
PAINT ORANGE (-810 2310);
FORCEPROP 2 LASTPIN (-800 2250) $PN 67
J 2
(-810 2260);
DISPLAY 0.617021 (-810 2260);
PAINT ORANGE (-810 2260);
FORCEPROP 2 LASTPIN (-800 2200) $PN 70
J 2
(-810 2210);
DISPLAY 0.617021 (-810 2210);
PAINT ORANGE (-810 2210);
FORCEPROP 2 LASTPIN (-800 2150) $PN 73
J 2
(-810 2160);
DISPLAY 0.617021 (-810 2160);
PAINT ORANGE (-810 2160);
FORCEPROP 2 LASTPIN (-800 2100) $PN 76
J 2
(-810 2110);
DISPLAY 0.617021 (-810 2110);
PAINT ORANGE (-810 2110);
FORCEPROP 2 LASTPIN (-800 2050) $PN 80
J 2
(-810 2060);
DISPLAY 0.617021 (-810 2060);
PAINT ORANGE (-810 2060);
FORCEPROP 2 LASTPIN (-800 2000) $PN 83
J 2
(-810 2010);
DISPLAY 0.617021 (-810 2010);
PAINT ORANGE (-810 2010);
FORCEPROP 2 LASTPIN (-800 1950) $PN 85
J 2
(-810 1960);
DISPLAY 0.617021 (-810 1960);
PAINT ORANGE (-810 1960);
FORCEPROP 2 LASTPIN (-800 1900) $PN 88
J 2
(-810 1910);
DISPLAY 0.617021 (-810 1910);
PAINT ORANGE (-810 1910);
FORCEPROP 2 LASTPIN (-800 1850) $PN 90
J 2
(-810 1860);
DISPLAY 0.617021 (-810 1860);
PAINT ORANGE (-810 1860);
FORCEPROP 2 LASTPIN (-800 1800) $PN 92
J 2
(-810 1810);
DISPLAY 0.617021 (-810 1810);
PAINT ORANGE (-810 1810);
FORCEPROP 2 LASTPIN (-800 1750) $PN 204
J 2
(-810 1760);
DISPLAY 0.617021 (-810 1760);
PAINT ORANGE (-810 1760);
FORCEPROP 2 LASTPIN (-800 1700) $PN 206
J 2
(-810 1710);
DISPLAY 0.617021 (-810 1710);
PAINT ORANGE (-810 1710);
FORCEPROP 2 LASTPIN (-800 1650) $PN 209
J 2
(-810 1660);
DISPLAY 0.617021 (-810 1660);
PAINT ORANGE (-810 1660);
FORCEPROP 2 LASTPIN (-800 1600) $PN 212
J 2
(-810 1610);
DISPLAY 0.617021 (-810 1610);
PAINT ORANGE (-810 1610);
FORCEPROP 2 LASTPIN (-800 1550) $PN 215
J 2
(-810 1560);
DISPLAY 0.617021 (-810 1560);
PAINT ORANGE (-810 1560);
FORCEPROP 2 LASTPIN (-800 1500) $PN 217
J 2
(-810 1510);
DISPLAY 0.617021 (-810 1510);
PAINT ORANGE (-810 1510);
FORCEPROP 2 LASTPIN (-800 1450) $PN 220
J 2
(-810 1460);
DISPLAY 0.617021 (-810 1460);
PAINT ORANGE (-810 1460);
FORCEPROP 2 LASTPIN (-800 1400) $PN 223
J 2
(-810 1410);
DISPLAY 0.617021 (-810 1410);
PAINT ORANGE (-810 1410);
FORCEPROP 2 LASTPIN (-800 1350) $PN 226
J 2
(-810 1360);
DISPLAY 0.617021 (-810 1360);
PAINT ORANGE (-810 1360);
FORCEPROP 2 LASTPIN (-800 1300) $PN 229
J 2
(-810 1310);
DISPLAY 0.617021 (-810 1310);
PAINT ORANGE (-810 1310);
FORCEPROP 2 LASTPIN (-800 1250) $PN 231
J 2
(-810 1260);
DISPLAY 0.617021 (-810 1260);
PAINT ORANGE (-810 1260);
FORCEPROP 2 LASTPIN (-800 1200) $PN 233
J 2
(-810 1210);
DISPLAY 0.617021 (-810 1210);
PAINT ORANGE (-810 1210);
FORCEPROP 2 LASTPIN (-800 1150) $PN 236
J 2
(-810 1160);
DISPLAY 0.617021 (-810 1160);
PAINT ORANGE (-810 1160);
FORCEPROP 2 LASTPIN (200 2850) $PN 1
J 0
(210 2860);
DISPLAY 0.617021 (210 2860);
PAINT ORANGE (210 2860);
FORCEPROP 2 LASTPIN (200 2800) $PN 145
J 0
(210 2810);
DISPLAY 0.617021 (210 2810);
PAINT ORANGE (210 2810);
FORCEPROP 1 LAST PACK_TYPE PIP
J 0
(-750 3150);
PAINT SKYBLUE (-750 3150);
DISPLAY INVISIBLE (-750 3150);
FORCEPROP 2 LAST SEC_TYPE PIP
J 0
(-750 3150);
DISPLAY 1.021277 (-750 3150);
PAINT ORANGE (-750 3150);
DISPLAY INVISIBLE (-750 3150);
FORCEPROP 2 LAST CDS_LIB mstr_sconn
J 0
(-300 2000);
PAINT ORANGE (-300 2000);
DISPLAY INVISIBLE (-300 2000);
FORCEPROP 2 LAST BOM_COST MEM
J 0
(-300 2000);
PAINT ORANGE (-300 2000);
DISPLAY INVISIBLE (-300 2000);
FORCEPROP 2 LAST SEC 4
J 0
(-750 3150);
DISPLAY 0.680851 (-750 3150);
PAINT MONO (-750 3150);
DISPLAY INVISIBLE (-750 3150);
FORCEPROP 2 LAST CDS_LOCATION J9L1
J 0
(-750 3100);
DISPLAY 0.617021 (-750 3100);
PAINT AQUA (-750 3100);
DISPLAY INVISIBLE (-750 3100);
FORCEPROP 1 LAST PATH I168
J 0
(-300 3050);
PAINT GREEN (-300 3050);
DISPLAY INVISIBLE (-300 3050);
FORCEPROP 2 LAST ROOM DDR4_CH_M
J 0
(-300 2000);
PAINT ORANGE (-300 2000);
DISPLAY INVISIBLE (-300 2000);
FORCEADD GND..1
R 2
(2500 1100);
FORCEPROP 3 LASTPIN (2500 1150) SIG_NAME GND\g
J 0
(2510 1160);
DISPLAY 0.659574 (2510 1160);
PAINT MONO (2510 1160);
DISPLAY INVISIBLE (2510 1160);
FORCEPROP 1 LAST VOLTAGE 0
J 0
(2500 1100);
PAINT SKYBLUE (2500 1100);
DISPLAY INVISIBLE (2500 1100);
FORCEPROP 2 LAST CDS_LIB mstr_symbols
J 0
(2500 1100);
DISPLAY 0.787234 (2500 1100);
PAINT MONO (2500 1100);
DISPLAY INVISIBLE (2500 1100);
FORCEPROP 1 LAST SIZE 1B
J 2
(2425 1050);
DISPLAY 1.170213 (2425 1050);
PAINT GREEN (2425 1050);
DISPLAY INVISIBLE (2425 1050);
FORCEPROP 2 LAST BOM_COST MEM
J 0
(2500 1105);
PAINT ORANGE (2500 1105);
DISPLAY INVISIBLE (2500 1105);
FORCEPROP 1 LAST BODY_TYPE PLUMBING
J 2
(2545 1057);
DISPLAY 0.340426 (2545 1057);
PAINT GREEN (2545 1057);
DISPLAY INVISIBLE (2545 1057);
FORCEPROP 1 LAST PATH I169
J 2
(2425 1100);
DISPLAY 1.404255 (2425 1100);
PAINT GREEN (2425 1100);
DISPLAY INVISIBLE (2425 1100);
FORCEPROP 2 LAST ROOM DDR4_CH_D
J 0
(2500 1105);
PAINT ORANGE (2500 1105);
DISPLAY INVISIBLE (2500 1105);
FORCEPROP 1 LAST HDL_POWER GND
J 2
(2500 1250);
DISPLAY 0.553191 (2500 1250);
PAINT GREEN (2500 1250);
DISPLAY INVISIBLE (2500 1250);
FORCEADD TAP..6
R 2
(900 4000);
FORCEPROP 3 LASTPIN (850 4000) SIG_NAME M_M_DQS_DN<6>
J 0
(860 4010);
DISPLAY 0.659574 (860 4010);
PAINT MONO (860 4010);
DISPLAY INVISIBLE (860 4010);
FORCEPROP 1 LASTPIN (850 4000) BN 6
J 2
(900 4010);
DISPLAY 0.617021 (900 4010);
PAINT PINK (900 4010);
FORCEPROP 2 LAST CDS_LIB mstr_standard
J 0
(900 4000);
DISPLAY 0.787234 (900 4000);
PAINT MONO (900 4000);
DISPLAY INVISIBLE (900 4000);
FORCEPROP 1 LAST BODY_TYPE PLUMBING
J 2
(900 3950);
DISPLAY 1.234043 (900 3950);
PAINT GREEN (900 3950);
DISPLAY INVISIBLE (900 3950);
FORCEPROP 1 LAST HDL_TAP TRUE
J 2
(575 3875);
DISPLAY 1.234043 (575 3875);
PAINT GREEN (575 3875);
DISPLAY INVISIBLE (575 3875);
FORCEPROP 1 LAST PATH I17
J 2
(900 4000);
DISPLAY 0.936170 (900 4000);
PAINT GREEN (900 4000);
DISPLAY INVISIBLE (900 4000);
FORCEADD OFFPAGE..1
(-3800 1700);
FORCEPROP 2 LAST $XR0 99 
J 0
(-4051 1700);
DISPLAY 0.638298 (-4051 1700);
PAINT MONO (-4051 1700);
FORCEPROP 2 LAST $XR1 83 
J 0
(-4141 1700);
DISPLAY 0.638298 (-4141 1700);
PAINT MONO (-4141 1700);
FORCEPROP 2 LAST $XR2 84 
J 0
(-4231 1700);
DISPLAY 0.638298 (-4231 1700);
PAINT MONO (-4231 1700);
FORCEPROP 2 LAST $XR3 85 
J 0
(-4321 1700);
DISPLAY 0.638298 (-4321 1700);
PAINT MONO (-4321 1700);
FORCEPROP 2 LAST $XR4 86 
J 0
(-4411 1700);
DISPLAY 0.638298 (-4411 1700);
PAINT MONO (-4411 1700);
FORCEPROP 2 LAST $XR5 87 
J 0
(-4501 1700);
DISPLAY 0.638298 (-4501 1700);
PAINT MONO (-4501 1700);
FORCEPROP 2 LAST CDS_LIB mstr_standard
J 0
(-3800 1700);
DISPLAY 0.787234 (-3800 1700);
PAINT MONO (-3800 1700);
DISPLAY INVISIBLE (-3800 1700);
FORCEPROP 1 LAST OFFPAGE TRUE
J 0
(-3475 1575);
DISPLAY 0.936170 (-3475 1575);
PAINT GREEN (-3475 1575);
DISPLAY INVISIBLE (-3475 1575);
FORCEPROP 1 LAST COMMENT_BODY TRUE
J 0
(-3675 1600);
DISPLAY 0.936170 (-3675 1600);
PAINT GREEN (-3675 1600);
DISPLAY INVISIBLE (-3675 1600);
FORCEPROP 2 LAST PATH I170
J 0
(-4075 1750);
DISPLAY 0.787234 (-4075 1750);
PAINT ORANGE (-4075 1750);
DISPLAY INVISIBLE (-4075 1750);
FORCEADD OFFPAGE..1
(-4800 1600);
FORCEPROP 2 LAST $XR0 100 
J 0
(-5082 1600);
DISPLAY 0.638298 (-5082 1600);
PAINT MONO (-5082 1600);
FORCEPROP 2 LAST $XR1 87 
J 0
(-5172 1600);
DISPLAY 0.638298 (-5172 1600);
PAINT MONO (-5172 1600);
FORCEPROP 2 LAST CDS_LIB mstr_standard
J 0
(-4800 1600);
DISPLAY 0.787234 (-4800 1600);
PAINT MONO (-4800 1600);
DISPLAY INVISIBLE (-4800 1600);
FORCEPROP 1 LAST OFFPAGE TRUE
J 0
(-4475 1475);
DISPLAY 0.936170 (-4475 1475);
PAINT GREEN (-4475 1475);
DISPLAY INVISIBLE (-4475 1475);
FORCEPROP 1 LAST COMMENT_BODY TRUE
J 0
(-4675 1500);
DISPLAY 0.936170 (-4675 1500);
PAINT GREEN (-4675 1500);
DISPLAY INVISIBLE (-4675 1500);
FORCEPROP 2 LAST PATH I171
J 0
(-5050 1650);
DISPLAY 0.787234 (-5050 1650);
PAINT ORANGE (-5050 1650);
DISPLAY INVISIBLE (-5050 1650);
FORCEADD OFFPAGE..6
(-3800 1750);
FORCEPROP 2 LAST $XR0 83 
J 0
(-4049 1750);
DISPLAY 0.638298 (-4049 1750);
PAINT MONO (-4049 1750);
FORCEPROP 2 LAST $XR1 84 
J 0
(-4139 1750);
DISPLAY 0.638298 (-4139 1750);
PAINT MONO (-4139 1750);
FORCEPROP 2 LAST $XR2 85 
J 0
(-4229 1750);
DISPLAY 0.638298 (-4229 1750);
PAINT MONO (-4229 1750);
FORCEPROP 2 LAST $XR3 86 
J 0
(-4319 1750);
DISPLAY 0.638298 (-4319 1750);
PAINT MONO (-4319 1750);
FORCEPROP 2 LAST $XR4 87 
J 0
(-4409 1750);
DISPLAY 0.638298 (-4409 1750);
PAINT MONO (-4409 1750);
FORCEPROP 2 LAST $XR5 99 
J 0
(-4499 1750);
DISPLAY 0.638298 (-4499 1750);
PAINT MONO (-4499 1750);
FORCEPROP 2 LASTPIN (-3750 1750) SIG_NAME SMB_DDR_KLM_VPP_SDA
J 0
(-3710 1760);
DISPLAY 0.617021 (-3710 1760);
PAINT ORANGE (-3710 1760);
FORCEPROP 2 LAST CDS_LIB mstr_standard
J 0
(-3800 1750);
DISPLAY 0.787234 (-3800 1750);
PAINT MONO (-3800 1750);
DISPLAY INVISIBLE (-3800 1750);
FORCEPROP 1 LAST OFFPAGE TRUE
J 0
(-3475 1625);
DISPLAY 0.936170 (-3475 1625);
PAINT GREEN (-3475 1625);
DISPLAY INVISIBLE (-3475 1625);
FORCEPROP 1 LAST COMMENT_BODY TRUE
J 0
(-3700 1675);
DISPLAY 0.936170 (-3700 1675);
PAINT GREEN (-3700 1675);
DISPLAY INVISIBLE (-3700 1675);
FORCEPROP 2 LAST PATH I172
J 0
(-4100 1800);
DISPLAY 0.787234 (-4100 1800);
PAINT ORANGE (-4100 1800);
DISPLAY INVISIBLE (-4100 1800);
FORCEADD OFFPAGE..5
(-4175 2450);
FORCEPROP 2 LAST $XR0 43 
J 0
(-4429 2450);
DISPLAY 0.638298 (-4429 2450);
PAINT MONO (-4429 2450);
FORCEPROP 2 LAST $XR1 44 
J 0
(-4519 2450);
DISPLAY 0.638298 (-4519 2450);
PAINT MONO (-4519 2450);
FORCEPROP 2 LAST $XR2 45 
J 0
(-4609 2450);
DISPLAY 0.638298 (-4609 2450);
PAINT MONO (-4609 2450);
FORCEPROP 2 LAST $XR3 46 
J 0
(-4699 2450);
DISPLAY 0.638298 (-4699 2450);
PAINT MONO (-4699 2450);
FORCEPROP 2 LAST $XR4 47 
J 0
(-4789 2450);
DISPLAY 0.638298 (-4789 2450);
PAINT MONO (-4789 2450);
FORCEPROP 2 LAST $XR5 48 
J 0
(-4879 2450);
DISPLAY 0.638298 (-4879 2450);
PAINT MONO (-4879 2450);
FORCEPROP 2 LAST $XR6 49 
J 0
(-4969 2450);
DISPLAY 0.638298 (-4969 2450);
PAINT MONO (-4969 2450);
FORCEPROP 2 LAST $XR7 50 
J 0
(-5059 2450);
DISPLAY 0.638298 (-5059 2450);
PAINT MONO (-5059 2450);
FORCEPROP 2 LAST $XR8 51 
J 0
(-5149 2450);
DISPLAY 0.638298 (-5149 2450);
PAINT MONO (-5149 2450);
FORCEPROP 2 LAST $XR9 52 
J 0
(-5239 2450);
DISPLAY 0.638298 (-5239 2450);
PAINT MONO (-5239 2450);
FORCEPROP 2 LAST $XR10 53 
J 0
(-4429 2414);
DISPLAY 0.638298 (-4429 2414);
PAINT MONO (-4429 2414);
FORCEPROP 2 LAST $XR11 54 
J 0
(-4519 2414);
DISPLAY 0.638298 (-4519 2414);
PAINT MONO (-4519 2414);
FORCEPROP 2 LAST $XR12 77 
J 0
(-4609 2414);
DISPLAY 0.638298 (-4609 2414);
PAINT MONO (-4609 2414);
FORCEPROP 2 LAST $XR13 78 
J 0
(-4699 2414);
DISPLAY 0.638298 (-4699 2414);
PAINT MONO (-4699 2414);
FORCEPROP 2 LAST $XR14 79 
J 0
(-4789 2414);
DISPLAY 0.638298 (-4789 2414);
PAINT MONO (-4789 2414);
FORCEPROP 2 LAST $XR15 80 
J 0
(-4879 2414);
DISPLAY 0.638298 (-4879 2414);
PAINT MONO (-4879 2414);
FORCEPROP 2 LAST $XR16 81 
J 0
(-4969 2414);
DISPLAY 0.638298 (-4969 2414);
PAINT MONO (-4969 2414);
FORCEPROP 2 LAST $XR17 82 
J 0
(-5059 2414);
DISPLAY 0.638298 (-5059 2414);
PAINT MONO (-5059 2414);
FORCEPROP 2 LAST $XR18 83 
J 0
(-5149 2414);
DISPLAY 0.638298 (-5149 2414);
PAINT MONO (-5149 2414);
FORCEPROP 2 LAST $XR19 84 
J 0
(-4429 2486);
DISPLAY 0.638298 (-4429 2486);
PAINT MONO (-4429 2486);
FORCEPROP 2 LAST $XR20 85 
J 0
(-4519 2486);
DISPLAY 0.638298 (-4519 2486);
PAINT MONO (-4519 2486);
FORCEPROP 2 LAST $XR21 86 
J 0
(-4609 2486);
DISPLAY 0.638298 (-4609 2486);
PAINT MONO (-4609 2486);
FORCEPROP 2 LAST $XR22 87 
J 0
(-4699 2486);
DISPLAY 0.638298 (-4699 2486);
PAINT MONO (-4699 2486);
FORCEPROP 2 LAST $XR23 94 
J 0
(-4789 2486);
DISPLAY 0.638298 (-4789 2486);
PAINT MONO (-4789 2486);
FORCEPROP 2 LAST CDS_LIB mstr_standard
J 0
(-4175 2450);
DISPLAY 0.787234 (-4175 2450);
PAINT MONO (-4175 2450);
DISPLAY INVISIBLE (-4175 2450);
FORCEPROP 1 LAST OFFPAGE TRUE
J 0
(-3850 2325);
DISPLAY 1.404255 (-3850 2325);
PAINT GREEN (-3850 2325);
DISPLAY INVISIBLE (-3850 2325);
FORCEPROP 1 LAST COMMENT_BODY TRUE
J 0
(-4075 2375);
DISPLAY 1.404255 (-4075 2375);
PAINT GREEN (-4075 2375);
DISPLAY INVISIBLE (-4075 2375);
FORCEPROP 2 LAST PATH I173
J 0
(-4125 2525);
DISPLAY 0.787234 (-4125 2525);
PAINT ORANGE (-4125 2525);
DISPLAY INVISIBLE (-4125 2525);
FORCEADD GND..1
R 2
(-5200 1725);
FORCEPROP 3 LASTPIN (-5200 1775) SIG_NAME GND\g
J 0
(-5190 1785);
DISPLAY 0.659574 (-5190 1785);
PAINT MONO (-5190 1785);
DISPLAY INVISIBLE (-5190 1785);
FORCEPROP 1 LAST VOLTAGE 0
J 0
(-5200 1725);
PAINT SKYBLUE (-5200 1725);
DISPLAY INVISIBLE (-5200 1725);
FORCEPROP 2 LAST BOM_COST MEM
J 0
(-5200 1730);
PAINT ORANGE (-5200 1730);
DISPLAY INVISIBLE (-5200 1730);
FORCEPROP 2 LAST CDS_LIB mstr_symbols
J 0
(-5200 1725);
DISPLAY 0.787234 (-5200 1725);
PAINT MONO (-5200 1725);
DISPLAY INVISIBLE (-5200 1725);
FORCEPROP 1 LAST SIZE 1B
J 2
(-5275 1675);
DISPLAY 1.170213 (-5275 1675);
PAINT GREEN (-5275 1675);
DISPLAY INVISIBLE (-5275 1675);
FORCEPROP 1 LAST BODY_TYPE PLUMBING
J 2
(-5155 1682);
DISPLAY 0.340426 (-5155 1682);
PAINT GREEN (-5155 1682);
DISPLAY INVISIBLE (-5155 1682);
FORCEPROP 1 LAST PATH I175
J 2
(-5275 1725);
DISPLAY 1.404255 (-5275 1725);
PAINT GREEN (-5275 1725);
DISPLAY INVISIBLE (-5275 1725);
FORCEPROP 2 LAST ROOM DDR4_CH_D
J 0
(-5200 1730);
PAINT ORANGE (-5200 1730);
DISPLAY INVISIBLE (-5200 1730);
FORCEPROP 1 LAST HDL_POWER GND
J 2
(-5200 1875);
DISPLAY 0.553191 (-5200 1875);
PAINT GREEN (-5200 1875);
DISPLAY INVISIBLE (-5200 1875);
FORCEADD GND..1
(-4650 1150);
FORCEPROP 3 LASTPIN (-4650 1200) SIG_NAME GND\g
J 0
(-4640 1210);
DISPLAY 0.659574 (-4640 1210);
PAINT MONO (-4640 1210);
DISPLAY INVISIBLE (-4640 1210);
FORCEPROP 1 LAST VOLTAGE 0
J 0
(-4650 1150);
PAINT SKYBLUE (-4650 1150);
DISPLAY INVISIBLE (-4650 1150);
FORCEPROP 1 LAST SIZE 1B
J 0
(-4575 1100);
DISPLAY 1.787234 (-4575 1100);
PAINT GREEN (-4575 1100);
DISPLAY INVISIBLE (-4575 1100);
FORCEPROP 2 LAST CDS_LIB mstr_symbols
J 0
(-4650 1150);
PAINT ORANGE (-4650 1150);
DISPLAY INVISIBLE (-4650 1150);
FORCEPROP 2 LAST BOM_COST MEM
J 0
(-4650 1155);
PAINT ORANGE (-4650 1155);
DISPLAY INVISIBLE (-4650 1155);
FORCEPROP 1 LAST BODY_TYPE PLUMBING
J 0
(-4695 1107);
DISPLAY 0.340426 (-4695 1107);
PAINT GREEN (-4695 1107);
DISPLAY INVISIBLE (-4695 1107);
FORCEPROP 1 LAST PATH I176
J 0
(-4575 1150);
DISPLAY 1.404255 (-4575 1150);
PAINT GREEN (-4575 1150);
DISPLAY INVISIBLE (-4575 1150);
FORCEPROP 2 LAST ROOM DDR4_CH_D
J 0
(-4650 1155);
PAINT ORANGE (-4650 1155);
DISPLAY INVISIBLE (-4650 1155);
FORCEPROP 1 LAST HDL_POWER GND
J 0
(-4650 1300);
DISPLAY 1.404255 (-4650 1300);
PAINT GREEN (-4650 1300);
DISPLAY INVISIBLE (-4650 1300);
FORCEADD CAP_A..1
R 2
(-4650 1400);
FORCEPROP 1 LAST LOCATION C9L1
J 2
(-4700 1500);
DISPLAY 0.617021 (-4700 1500);
PAINT AQUA (-4700 1500);
FORCEPROP 1 LAST PART_NUMBER A36096-045
J 2
(-4700 1250);
DISPLAY 0.617021 (-4700 1250);
PAINT BLUE (-4700 1250);
FORCEPROP 1 LAST VALUE 0.01UF
J 2
(-4700 1450);
DISPLAY 0.617021 (-4700 1450);
PAINT SKYBLUE (-4700 1450);
FORCEPROP 1 LAST TOLERANCE 10%
J 2
(-4700 1350);
DISPLAY 0.617021 (-4700 1350);
PAINT SKYBLUE (-4700 1350);
FORCEPROP 1 LAST PACK_TYPE 0402V
J 2
(-4700 1200);
DISPLAY 0.617021 (-4700 1200);
PAINT SKYBLUE (-4700 1200);
FORCEPROP 1 LAST VOLTAGE 25V
J 2
(-4700 1400);
DISPLAY 0.617021 (-4700 1400);
PAINT SKYBLUE (-4700 1400);
FORCEPROP 1 LAST MATERIAL X7R
J 2
(-4700 1300);
DISPLAY 0.617021 (-4700 1300);
PAINT SKYBLUE (-4700 1300);
FORCEPROP 1 LASTPIN (-4650 1500) $PN 1
J 2
(-4660 1480);
DISPLAY 0.617021 (-4660 1480);
PAINT ORANGE (-4660 1480);
FORCEPROP 1 LASTPIN (-4650 1300) $PN 2
J 2
(-4660 1280);
DISPLAY 0.617021 (-4660 1280);
PAINT ORANGE (-4660 1280);
FORCEPROP 2 LAST CDS_LOCATION C9L1
J 2
(-4700 1500);
DISPLAY 0.617021 (-4700 1500);
PAINT AQUA (-4700 1500);
DISPLAY INVISIBLE (-4700 1500);
FORCEPROP 2 LAST BOM_COST MEM
J 0
(-4650 1400);
PAINT ORANGE (-4650 1400);
DISPLAY INVISIBLE (-4650 1400);
FORCEPROP 2 LAST CDS_LIB dev_discrete
J 0
(-4650 1400);
PAINT ORANGE (-4650 1400);
DISPLAY INVISIBLE (-4650 1400);
FORCEPROP 2 LAST CDS_SEC 1
J 0
(-4700 1550);
PAINT ORANGE (-4700 1550);
DISPLAY INVISIBLE (-4700 1550);
FORCEPROP 2 LAST SEC_TYPE 0402V
J 0
(-4700 1600);
DISPLAY 1.021277 (-4700 1600);
PAINT ORANGE (-4700 1600);
DISPLAY INVISIBLE (-4700 1600);
FORCEPROP 2 LAST SEC 1
J 0
(-4700 1600);
DISPLAY 0.680851 (-4700 1600);
PAINT MONO (-4700 1600);
DISPLAY INVISIBLE (-4700 1600);
FORCEPROP 1 LAST PATH I177
J 2
(-4700 1550);
DISPLAY 0.978723 (-4700 1550);
PAINT WHITE (-4700 1550);
DISPLAY INVISIBLE (-4700 1550);
FORCEPROP 2 LAST ROOM DDR4_CH_M1
J 0
(-4650 1400);
PAINT ORANGE (-4650 1400);
DISPLAY INVISIBLE (-4650 1400);
FORCEADD PVPP_KLM..1
(-5200 2100);
FORCEPROP 3 LASTPIN (-5200 2050) SIG_NAME PVPP_KLM\g
J 0
(-5190 2060);
DISPLAY 0.659574 (-5190 2060);
PAINT MONO (-5190 2060);
DISPLAY INVISIBLE (-5190 2060);
FORCEPROP 1 LAST VOLTAGE 2.5V
J 0
(-5245 2057);
DISPLAY 0.340426 (-5245 2057);
PAINT SKYBLUE (-5245 2057);
DISPLAY INVISIBLE (-5245 2057);
FORCEPROP 0 LAST BOM_COST MEM
J 0
(-5200 2200);
PAINT ORANGE (-5200 2200);
DISPLAY INVISIBLE (-5200 2200);
FORCEPROP 2 LAST CDS_LIB mstr_symbols
J 0
(-5200 2100);
PAINT ORANGE (-5200 2100);
DISPLAY INVISIBLE (-5200 2100);
FORCEPROP 1 LAST BODY_TYPE PLUMBING
J 0
(-5245 2057);
DISPLAY 0.340426 (-5245 2057);
PAINT GREEN (-5245 2057);
DISPLAY INVISIBLE (-5245 2057);
FORCEPROP 1 LAST PATH I178
J 0
(-5150 2125);
DISPLAY 0.872340 (-5150 2125);
PAINT AQUA (-5150 2125);
DISPLAY INVISIBLE (-5150 2125);
FORCEPROP 2 LAST ROOM DDR4_CH_D
J 0
(-5200 2200);
PAINT ORANGE (-5200 2200);
DISPLAY INVISIBLE (-5200 2200);
FORCEPROP 1 LAST HDL_POWER PVPP_KLM
J 1
(-5200 2150);
DISPLAY 0.872340 (-5200 2150);
PAINT GREEN (-5200 2150);
DISPLAY INVISIBLE (-5200 2150);
FORCEADD PVPP_KLM..1
(-1000 3025);
FORCEPROP 3 LASTPIN (-1000 2975) SIG_NAME PVPP_KLM\g
J 0
(-990 2985);
DISPLAY 0.659574 (-990 2985);
PAINT MONO (-990 2985);
DISPLAY INVISIBLE (-990 2985);
FORCEPROP 1 LAST VOLTAGE 2.5V
J 0
(-1045 2982);
DISPLAY 0.340426 (-1045 2982);
PAINT SKYBLUE (-1045 2982);
DISPLAY INVISIBLE (-1045 2982);
FORCEPROP 0 LAST BOM_COST MEM
J 0
(-1000 3125);
PAINT ORANGE (-1000 3125);
DISPLAY INVISIBLE (-1000 3125);
FORCEPROP 2 LAST CDS_LIB mstr_symbols
J 0
(-1000 3025);
PAINT ORANGE (-1000 3025);
DISPLAY INVISIBLE (-1000 3025);
FORCEPROP 1 LAST BODY_TYPE PLUMBING
J 0
(-1045 2982);
DISPLAY 0.340426 (-1045 2982);
PAINT GREEN (-1045 2982);
DISPLAY INVISIBLE (-1045 2982);
FORCEPROP 1 LAST PATH I179
J 0
(-950 3050);
DISPLAY 0.872340 (-950 3050);
PAINT AQUA (-950 3050);
DISPLAY INVISIBLE (-950 3050);
FORCEPROP 2 LAST ROOM DDR4_CH_D
J 0
(-1000 3125);
PAINT ORANGE (-1000 3125);
DISPLAY INVISIBLE (-1000 3125);
FORCEPROP 1 LAST HDL_POWER PVPP_KLM
J 1
(-1000 3075);
DISPLAY 0.872340 (-1000 3075);
PAINT GREEN (-1000 3075);
DISPLAY INVISIBLE (-1000 3075);
FORCEADD TAP..6
R 2
(900 3900);
FORCEPROP 3 LASTPIN (850 3900) SIG_NAME M_M_DQS_DN<5>
J 0
(860 3910);
DISPLAY 0.659574 (860 3910);
PAINT MONO (860 3910);
DISPLAY INVISIBLE (860 3910);
FORCEPROP 1 LASTPIN (850 3900) BN 5
J 2
(900 3910);
DISPLAY 0.617021 (900 3910);
PAINT PINK (900 3910);
FORCEPROP 2 LAST CDS_LIB mstr_standard
J 0
(900 3900);
DISPLAY 0.787234 (900 3900);
PAINT MONO (900 3900);
DISPLAY INVISIBLE (900 3900);
FORCEPROP 1 LAST BODY_TYPE PLUMBING
J 2
(900 3850);
DISPLAY 1.234043 (900 3850);
PAINT GREEN (900 3850);
DISPLAY INVISIBLE (900 3850);
FORCEPROP 1 LAST HDL_TAP TRUE
J 2
(575 3775);
DISPLAY 1.234043 (575 3775);
PAINT GREEN (575 3775);
DISPLAY INVISIBLE (575 3775);
FORCEPROP 1 LAST PATH I18
J 2
(900 3900);
DISPLAY 0.936170 (900 3900);
PAINT GREEN (900 3900);
DISPLAY INVISIBLE (900 3900);
FORCEADD OFFPAGE..1
(-3850 1300);
FORCEPROP 2 LAST $XR0 89 
J 0
(-4101 1300);
DISPLAY 0.638298 (-4101 1300);
PAINT MONO (-4101 1300);
FORCEPROP 2 LAST $XR1 83 
J 0
(-4191 1300);
DISPLAY 0.638298 (-4191 1300);
PAINT MONO (-4191 1300);
FORCEPROP 2 LAST $XR2 84 
J 0
(-4281 1300);
DISPLAY 0.638298 (-4281 1300);
PAINT MONO (-4281 1300);
FORCEPROP 2 LAST $XR3 85 
J 0
(-4371 1300);
DISPLAY 0.638298 (-4371 1300);
PAINT MONO (-4371 1300);
FORCEPROP 2 LAST $XR4 86 
J 0
(-4461 1300);
DISPLAY 0.638298 (-4461 1300);
PAINT MONO (-4461 1300);
FORCEPROP 2 LAST $XR5 87 
J 0
(-4551 1300);
DISPLAY 0.638298 (-4551 1300);
PAINT MONO (-4551 1300);
FORCEPROP 2 LAST CDS_LIB mstr_standard
J 0
(-3850 1300);
PAINT ORANGE (-3850 1300);
DISPLAY INVISIBLE (-3850 1300);
FORCEPROP 1 LAST OFFPAGE TRUE
J 0
(-3525 1175);
DISPLAY 0.936170 (-3525 1175);
PAINT GREEN (-3525 1175);
DISPLAY INVISIBLE (-3525 1175);
FORCEPROP 1 LAST COMMENT_BODY TRUE
J 0
(-3725 1200);
DISPLAY 0.936170 (-3725 1200);
PAINT GREEN (-3725 1200);
DISPLAY INVISIBLE (-3725 1200);
FORCEPROP 2 LAST PATH I180
J 0
(-3800 1375);
PAINT ORANGE (-3800 1375);
DISPLAY INVISIBLE (-3800 1375);
FORCEADD TAP..6
(-3650 3550);
FORCEPROP 3 LASTPIN (-3600 3550) SIG_NAME M_M_CLK_DP<3>
J 0
(-3590 3560);
DISPLAY 0.659574 (-3590 3560);
PAINT MONO (-3590 3560);
DISPLAY INVISIBLE (-3590 3560);
FORCEPROP 1 LASTPIN (-3600 3550) BN 3
J 0
(-3652 3558);
DISPLAY 0.617021 (-3652 3558);
PAINT PINK (-3652 3558);
FORCEPROP 2 LAST CDS_LIB mstr_standard
J 0
(-3650 3550);
PAINT MONO (-3650 3550);
DISPLAY INVISIBLE (-3650 3550);
FORCEPROP 1 LAST BODY_TYPE PLUMBING
J 0
(-3650 3500);
DISPLAY 1.234043 (-3650 3500);
PAINT GREEN (-3650 3500);
DISPLAY INVISIBLE (-3650 3500);
FORCEPROP 1 LAST HDL_TAP TRUE
J 0
(-3325 3425);
DISPLAY 1.234043 (-3325 3425);
PAINT GREEN (-3325 3425);
DISPLAY INVISIBLE (-3325 3425);
FORCEPROP 1 LAST PATH I184
J 0
(-3652 3550);
DISPLAY 0.872340 (-3652 3550);
PAINT GREEN (-3652 3550);
DISPLAY INVISIBLE (-3652 3550);
FORCEADD TAP..6
(-3800 3500);
FORCEPROP 3 LASTPIN (-3750 3500) SIG_NAME M_M_CLK_DN<3>
J 0
(-3740 3510);
DISPLAY 0.659574 (-3740 3510);
PAINT MONO (-3740 3510);
DISPLAY INVISIBLE (-3740 3510);
FORCEPROP 1 LASTPIN (-3750 3500) BN 3
J 0
(-3802 3508);
DISPLAY 0.617021 (-3802 3508);
PAINT PINK (-3802 3508);
FORCEPROP 2 LAST CDS_LIB mstr_standard
J 0
(-3800 3500);
PAINT MONO (-3800 3500);
DISPLAY INVISIBLE (-3800 3500);
FORCEPROP 1 LAST BODY_TYPE PLUMBING
J 0
(-3800 3450);
DISPLAY 1.234043 (-3800 3450);
PAINT GREEN (-3800 3450);
DISPLAY INVISIBLE (-3800 3450);
FORCEPROP 1 LAST HDL_TAP TRUE
J 0
(-3475 3375);
DISPLAY 1.234043 (-3475 3375);
PAINT GREEN (-3475 3375);
DISPLAY INVISIBLE (-3475 3375);
FORCEPROP 1 LAST PATH I185
J 0
(-3802 3500);
DISPLAY 0.872340 (-3802 3500);
PAINT GREEN (-3802 3500);
DISPLAY INVISIBLE (-3802 3500);
FORCEADD P12V_NVDIMM_KLM..1
(400 3000);
FORCEPROP 3 LASTPIN (400 2950) SIG_NAME P12V_NVDIMM_KLM\g
J 0
(410 2960);
DISPLAY 0.659574 (410 2960);
PAINT MONO (410 2960);
DISPLAY INVISIBLE (410 2960);
FORCEPROP 1 LAST VOLTAGE 12.0
J 0
(355 2957);
DISPLAY 0.340426 (355 2957);
PAINT SKYBLUE (355 2957);
DISPLAY INVISIBLE (355 2957);
FORCEPROP 2 LAST CDS_LIB mstr_symbols
J 0
(400 3000);
PAINT ORANGE (400 3000);
DISPLAY INVISIBLE (400 3000);
FORCEPROP 1 LAST BODY_TYPE PLUMBING
J 0
(355 2957);
DISPLAY 0.340426 (355 2957);
PAINT GREEN (355 2957);
DISPLAY INVISIBLE (355 2957);
FORCEPROP 1 LAST PATH I186
J 0
(450 3025);
DISPLAY 0.872340 (450 3025);
PAINT AQUA (450 3025);
DISPLAY INVISIBLE (450 3025);
FORCEPROP 1 LAST HDL_POWER P12V_NVDIMM_KLM
J 1
(400 3050);
DISPLAY 0.872340 (400 3050);
PAINT GREEN (400 3050);
DISPLAY INVISIBLE (400 3050);
FORCEADD TAP..6
R 2
(900 3800);
FORCEPROP 3 LASTPIN (850 3800) SIG_NAME M_M_DQS_DN<4>
J 0
(860 3810);
DISPLAY 0.659574 (860 3810);
PAINT MONO (860 3810);
DISPLAY INVISIBLE (860 3810);
FORCEPROP 1 LASTPIN (850 3800) BN 4
J 2
(900 3810);
DISPLAY 0.617021 (900 3810);
PAINT PINK (900 3810);
FORCEPROP 2 LAST CDS_LIB mstr_standard
J 0
(900 3800);
DISPLAY 0.787234 (900 3800);
PAINT MONO (900 3800);
DISPLAY INVISIBLE (900 3800);
FORCEPROP 1 LAST BODY_TYPE PLUMBING
J 2
(900 3750);
DISPLAY 1.234043 (900 3750);
PAINT GREEN (900 3750);
DISPLAY INVISIBLE (900 3750);
FORCEPROP 1 LAST HDL_TAP TRUE
J 2
(575 3675);
DISPLAY 1.234043 (575 3675);
PAINT GREEN (575 3675);
DISPLAY INVISIBLE (575 3675);
FORCEPROP 1 LAST PATH I19
J 2
(900 3800);
DISPLAY 0.936170 (900 3800);
PAINT GREEN (900 3800);
DISPLAY INVISIBLE (900 3800);
FORCEADD OFFPAGE..3
(1600 5150);
FORCEPROP 2 LAST $XR0 62 
J 0
(1814 5150);
DISPLAY 0.638298 (1814 5150);
PAINT MONO (1814 5150);
FORCEPROP 2 LAST $XR1 87 
J 0
(1904 5150);
DISPLAY 0.638298 (1904 5150);
PAINT MONO (1904 5150);
FORCEPROP 2 LAST CDS_LIB mstr_standard
J 0
(1600 5150);
DISPLAY 0.787234 (1600 5150);
PAINT MONO (1600 5150);
DISPLAY INVISIBLE (1600 5150);
FORCEPROP 1 LAST OFFPAGE TRUE
J 0
(1925 5025);
DISPLAY 0.936170 (1925 5025);
PAINT GREEN (1925 5025);
DISPLAY INVISIBLE (1925 5025);
FORCEPROP 1 LAST COMMENT_BODY TRUE
J 0
(1550 5050);
DISPLAY 0.936170 (1550 5050);
PAINT GREEN (1550 5050);
DISPLAY INVISIBLE (1550 5050);
FORCEPROP 2 LAST PATH I2
J 0
(1800 5225);
DISPLAY 0.787234 (1800 5225);
PAINT MONO (1800 5225);
DISPLAY INVISIBLE (1800 5225);
FORCEADD TAP..6
R 2
(900 3700);
FORCEPROP 3 LASTPIN (850 3700) SIG_NAME M_M_DQS_DN<3>
J 0
(860 3710);
DISPLAY 0.659574 (860 3710);
PAINT MONO (860 3710);
DISPLAY INVISIBLE (860 3710);
FORCEPROP 1 LASTPIN (850 3700) BN 3
J 2
(900 3710);
DISPLAY 0.617021 (900 3710);
PAINT PINK (900 3710);
FORCEPROP 2 LAST CDS_LIB mstr_standard
J 0
(900 3700);
DISPLAY 0.787234 (900 3700);
PAINT MONO (900 3700);
DISPLAY INVISIBLE (900 3700);
FORCEPROP 1 LAST BODY_TYPE PLUMBING
J 2
(900 3650);
DISPLAY 1.234043 (900 3650);
PAINT GREEN (900 3650);
DISPLAY INVISIBLE (900 3650);
FORCEPROP 1 LAST HDL_TAP TRUE
J 2
(575 3575);
DISPLAY 1.234043 (575 3575);
PAINT GREEN (575 3575);
DISPLAY INVISIBLE (575 3575);
FORCEPROP 1 LAST PATH I20
J 2
(900 3700);
DISPLAY 0.936170 (900 3700);
PAINT GREEN (900 3700);
DISPLAY INVISIBLE (900 3700);
FORCEADD TAP..6
R 2
(900 3500);
FORCEPROP 3 LASTPIN (850 3500) SIG_NAME M_M_DQS_DN<1>
J 0
(860 3510);
DISPLAY 0.659574 (860 3510);
PAINT MONO (860 3510);
DISPLAY INVISIBLE (860 3510);
FORCEPROP 1 LASTPIN (850 3500) BN 1
J 2
(900 3510);
DISPLAY 0.617021 (900 3510);
PAINT PINK (900 3510);
FORCEPROP 2 LAST CDS_LIB mstr_standard
J 0
(900 3500);
DISPLAY 0.787234 (900 3500);
PAINT MONO (900 3500);
DISPLAY INVISIBLE (900 3500);
FORCEPROP 1 LAST BODY_TYPE PLUMBING
J 2
(900 3450);
DISPLAY 1.234043 (900 3450);
PAINT GREEN (900 3450);
DISPLAY INVISIBLE (900 3450);
FORCEPROP 1 LAST HDL_TAP TRUE
J 2
(575 3375);
DISPLAY 1.234043 (575 3375);
PAINT GREEN (575 3375);
DISPLAY INVISIBLE (575 3375);
FORCEPROP 1 LAST PATH I21
J 2
(900 3500);
DISPLAY 0.936170 (900 3500);
PAINT GREEN (900 3500);
DISPLAY INVISIBLE (900 3500);
FORCEADD TAP..6
R 2
(900 3600);
FORCEPROP 3 LASTPIN (850 3600) SIG_NAME M_M_DQS_DN<2>
J 0
(860 3610);
DISPLAY 0.659574 (860 3610);
PAINT MONO (860 3610);
DISPLAY INVISIBLE (860 3610);
FORCEPROP 1 LASTPIN (850 3600) BN 2
J 2
(900 3610);
DISPLAY 0.617021 (900 3610);
PAINT PINK (900 3610);
FORCEPROP 2 LAST CDS_LIB mstr_standard
J 0
(900 3600);
DISPLAY 0.787234 (900 3600);
PAINT MONO (900 3600);
DISPLAY INVISIBLE (900 3600);
FORCEPROP 1 LAST BODY_TYPE PLUMBING
J 2
(900 3550);
DISPLAY 1.234043 (900 3550);
PAINT GREEN (900 3550);
DISPLAY INVISIBLE (900 3550);
FORCEPROP 1 LAST HDL_TAP TRUE
J 2
(575 3475);
DISPLAY 1.234043 (575 3475);
PAINT GREEN (575 3475);
DISPLAY INVISIBLE (575 3475);
FORCEPROP 1 LAST PATH I22
J 2
(900 3600);
DISPLAY 0.936170 (900 3600);
PAINT GREEN (900 3600);
DISPLAY INVISIBLE (900 3600);
FORCEADD TAP..6
R 2
(900 3400);
FORCEPROP 3 LASTPIN (850 3400) SIG_NAME M_M_DQS_DN<0>
J 0
(860 3410);
DISPLAY 0.659574 (860 3410);
PAINT MONO (860 3410);
DISPLAY INVISIBLE (860 3410);
FORCEPROP 1 LASTPIN (850 3400) BN 0
J 2
(900 3410);
DISPLAY 0.617021 (900 3410);
PAINT PINK (900 3410);
FORCEPROP 2 LAST CDS_LIB mstr_standard
J 0
(900 3400);
DISPLAY 0.787234 (900 3400);
PAINT MONO (900 3400);
DISPLAY INVISIBLE (900 3400);
FORCEPROP 1 LAST BODY_TYPE PLUMBING
J 2
(900 3350);
DISPLAY 1.234043 (900 3350);
PAINT GREEN (900 3350);
DISPLAY INVISIBLE (900 3350);
FORCEPROP 1 LAST HDL_TAP TRUE
J 2
(575 3275);
DISPLAY 1.234043 (575 3275);
PAINT GREEN (575 3275);
DISPLAY INVISIBLE (575 3275);
FORCEPROP 1 LAST PATH I23
J 2
(900 3400);
DISPLAY 0.936170 (900 3400);
PAINT GREEN (900 3400);
DISPLAY INVISIBLE (900 3400);
FORCEADD SCONN288_H44441003..3
(1800 2400);
FORCEPROP 1 LAST LOCATION J9L1
J 0
(1350 3800);
DISPLAY 0.617021 (1350 3800);
PAINT AQUA (1350 3800);
FORCEPROP 1 LAST PART_NUMBER H44441-003
J 0
(1350 1050);
DISPLAY 0.617021 (1350 1050);
PAINT BLUE (1350 1050);
FORCEPROP 1 LAST MATERIAL SCONN
J 0
(1350 3750);
DISPLAY 0.617021 (1350 3750);
PAINT SKYBLUE (1350 3750);
FORCEPROP 2 LASTPIN (1300 3550) $PN 2
J 2
(1290 3560);
DISPLAY 0.617021 (1290 3560);
PAINT ORANGE (1290 3560);
FORCEPROP 2 LASTPIN (1300 3500) $PN 4
J 2
(1290 3510);
DISPLAY 0.617021 (1290 3510);
PAINT ORANGE (1290 3510);
FORCEPROP 2 LASTPIN (1300 3450) $PN 6
J 2
(1290 3460);
DISPLAY 0.617021 (1290 3460);
PAINT ORANGE (1290 3460);
FORCEPROP 2 LASTPIN (1300 3400) $PN 9
J 2
(1290 3410);
DISPLAY 0.617021 (1290 3410);
PAINT ORANGE (1290 3410);
FORCEPROP 2 LASTPIN (1300 3350) $PN 11
J 2
(1290 3360);
DISPLAY 0.617021 (1290 3360);
PAINT ORANGE (1290 3360);
FORCEPROP 2 LASTPIN (1300 3300) $PN 13
J 2
(1290 3310);
DISPLAY 0.617021 (1290 3310);
PAINT ORANGE (1290 3310);
FORCEPROP 2 LASTPIN (1300 3250) $PN 15
J 2
(1290 3260);
DISPLAY 0.617021 (1290 3260);
PAINT ORANGE (1290 3260);
FORCEPROP 2 LASTPIN (1300 3200) $PN 17
J 2
(1290 3210);
DISPLAY 0.617021 (1290 3210);
PAINT ORANGE (1290 3210);
FORCEPROP 2 LASTPIN (1300 3150) $PN 20
J 2
(1290 3160);
DISPLAY 0.617021 (1290 3160);
PAINT ORANGE (1290 3160);
FORCEPROP 2 LASTPIN (1300 3100) $PN 22
J 2
(1290 3110);
DISPLAY 0.617021 (1290 3110);
PAINT ORANGE (1290 3110);
FORCEPROP 2 LASTPIN (1300 3050) $PN 24
J 2
(1290 3060);
DISPLAY 0.617021 (1290 3060);
PAINT ORANGE (1290 3060);
FORCEPROP 2 LASTPIN (1300 3000) $PN 26
J 2
(1290 3010);
DISPLAY 0.617021 (1290 3010);
PAINT ORANGE (1290 3010);
FORCEPROP 2 LASTPIN (1300 2950) $PN 28
J 2
(1290 2960);
DISPLAY 0.617021 (1290 2960);
PAINT ORANGE (1290 2960);
FORCEPROP 2 LASTPIN (1300 2900) $PN 31
J 2
(1290 2910);
DISPLAY 0.617021 (1290 2910);
PAINT ORANGE (1290 2910);
FORCEPROP 2 LASTPIN (1300 2850) $PN 33
J 2
(1290 2860);
DISPLAY 0.617021 (1290 2860);
PAINT ORANGE (1290 2860);
FORCEPROP 2 LASTPIN (1300 2800) $PN 35
J 2
(1290 2810);
DISPLAY 0.617021 (1290 2810);
PAINT ORANGE (1290 2810);
FORCEPROP 2 LASTPIN (1300 2750) $PN 37
J 2
(1290 2760);
DISPLAY 0.617021 (1290 2760);
PAINT ORANGE (1290 2760);
FORCEPROP 2 LASTPIN (1300 2700) $PN 39
J 2
(1290 2710);
DISPLAY 0.617021 (1290 2710);
PAINT ORANGE (1290 2710);
FORCEPROP 2 LASTPIN (1300 2650) $PN 42
J 2
(1290 2660);
DISPLAY 0.617021 (1290 2660);
PAINT ORANGE (1290 2660);
FORCEPROP 2 LASTPIN (1300 2600) $PN 44
J 2
(1290 2610);
DISPLAY 0.617021 (1290 2610);
PAINT ORANGE (1290 2610);
FORCEPROP 2 LASTPIN (1300 2550) $PN 46
J 2
(1290 2560);
DISPLAY 0.617021 (1290 2560);
PAINT ORANGE (1290 2560);
FORCEPROP 2 LASTPIN (1300 2500) $PN 48
J 2
(1290 2510);
DISPLAY 0.617021 (1290 2510);
PAINT ORANGE (1290 2510);
FORCEPROP 2 LASTPIN (1300 2450) $PN 50
J 2
(1290 2460);
DISPLAY 0.617021 (1290 2460);
PAINT ORANGE (1290 2460);
FORCEPROP 2 LASTPIN (1300 2400) $PN 53
J 2
(1290 2410);
DISPLAY 0.617021 (1290 2410);
PAINT ORANGE (1290 2410);
FORCEPROP 2 LASTPIN (1300 2350) $PN 55
J 2
(1290 2360);
DISPLAY 0.617021 (1290 2360);
PAINT ORANGE (1290 2360);
FORCEPROP 2 LASTPIN (1300 2300) $PN 57
J 2
(1290 2310);
DISPLAY 0.617021 (1290 2310);
PAINT ORANGE (1290 2310);
FORCEPROP 2 LASTPIN (1300 2250) $PN 94
J 2
(1290 2260);
DISPLAY 0.617021 (1290 2260);
PAINT ORANGE (1290 2260);
FORCEPROP 2 LASTPIN (1300 2200) $PN 96
J 2
(1290 2210);
DISPLAY 0.617021 (1290 2210);
PAINT ORANGE (1290 2210);
FORCEPROP 2 LASTPIN (1300 2150) $PN 98
J 2
(1290 2160);
DISPLAY 0.617021 (1290 2160);
PAINT ORANGE (1290 2160);
FORCEPROP 2 LASTPIN (1300 2100) $PN 101
J 2
(1290 2110);
DISPLAY 0.617021 (1290 2110);
PAINT ORANGE (1290 2110);
FORCEPROP 2 LASTPIN (1300 2050) $PN 103
J 2
(1290 2060);
DISPLAY 0.617021 (1290 2060);
PAINT ORANGE (1290 2060);
FORCEPROP 2 LASTPIN (1300 2000) $PN 105
J 2
(1290 2010);
DISPLAY 0.617021 (1290 2010);
PAINT ORANGE (1290 2010);
FORCEPROP 2 LASTPIN (1300 1950) $PN 107
J 2
(1290 1960);
DISPLAY 0.617021 (1290 1960);
PAINT ORANGE (1290 1960);
FORCEPROP 2 LASTPIN (1300 1900) $PN 109
J 2
(1290 1910);
DISPLAY 0.617021 (1290 1910);
PAINT ORANGE (1290 1910);
FORCEPROP 2 LASTPIN (1300 1850) $PN 112
J 2
(1290 1860);
DISPLAY 0.617021 (1290 1860);
PAINT ORANGE (1290 1860);
FORCEPROP 2 LASTPIN (1300 1800) $PN 114
J 2
(1290 1810);
DISPLAY 0.617021 (1290 1810);
PAINT ORANGE (1290 1810);
FORCEPROP 2 LASTPIN (1300 1750) $PN 116
J 2
(1290 1760);
DISPLAY 0.617021 (1290 1760);
PAINT ORANGE (1290 1760);
FORCEPROP 2 LASTPIN (1300 1700) $PN 118
J 2
(1290 1710);
DISPLAY 0.617021 (1290 1710);
PAINT ORANGE (1290 1710);
FORCEPROP 2 LASTPIN (1300 1650) $PN 120
J 2
(1290 1660);
DISPLAY 0.617021 (1290 1660);
PAINT ORANGE (1290 1660);
FORCEPROP 2 LASTPIN (1300 1600) $PN 123
J 2
(1290 1610);
DISPLAY 0.617021 (1290 1610);
PAINT ORANGE (1290 1610);
FORCEPROP 2 LASTPIN (1300 1550) $PN 125
J 2
(1290 1560);
DISPLAY 0.617021 (1290 1560);
PAINT ORANGE (1290 1560);
FORCEPROP 2 LASTPIN (1300 1500) $PN 127
J 2
(1290 1510);
DISPLAY 0.617021 (1290 1510);
PAINT ORANGE (1290 1510);
FORCEPROP 2 LASTPIN (1300 1450) $PN 129
J 2
(1290 1460);
DISPLAY 0.617021 (1290 1460);
PAINT ORANGE (1290 1460);
FORCEPROP 2 LASTPIN (1300 1400) $PN 131
J 2
(1290 1410);
DISPLAY 0.617021 (1290 1410);
PAINT ORANGE (1290 1410);
FORCEPROP 2 LASTPIN (1300 1350) $PN 134
J 2
(1290 1360);
DISPLAY 0.617021 (1290 1360);
PAINT ORANGE (1290 1360);
FORCEPROP 2 LASTPIN (1300 1300) $PN 136
J 2
(1290 1310);
DISPLAY 0.617021 (1290 1310);
PAINT ORANGE (1290 1310);
FORCEPROP 2 LASTPIN (1300 1250) $PN 138
J 2
(1290 1260);
DISPLAY 0.617021 (1290 1260);
PAINT ORANGE (1290 1260);
FORCEPROP 2 LASTPIN (2300 3550) $PN 147
J 0
(2310 3560);
DISPLAY 0.617021 (2310 3560);
PAINT ORANGE (2310 3560);
FORCEPROP 2 LASTPIN (2300 3500) $PN 149
J 0
(2310 3510);
DISPLAY 0.617021 (2310 3510);
PAINT ORANGE (2310 3510);
FORCEPROP 2 LASTPIN (2300 3450) $PN 151
J 0
(2310 3460);
DISPLAY 0.617021 (2310 3460);
PAINT ORANGE (2310 3460);
FORCEPROP 2 LASTPIN (2300 3400) $PN 154
J 0
(2310 3410);
DISPLAY 0.617021 (2310 3410);
PAINT ORANGE (2310 3410);
FORCEPROP 2 LASTPIN (2300 3350) $PN 156
J 0
(2310 3360);
DISPLAY 0.617021 (2310 3360);
PAINT ORANGE (2310 3360);
FORCEPROP 2 LASTPIN (2300 3300) $PN 158
J 0
(2310 3310);
DISPLAY 0.617021 (2310 3310);
PAINT ORANGE (2310 3310);
FORCEPROP 2 LASTPIN (2300 3250) $PN 160
J 0
(2310 3260);
DISPLAY 0.617021 (2310 3260);
PAINT ORANGE (2310 3260);
FORCEPROP 2 LASTPIN (2300 3200) $PN 162
J 0
(2310 3210);
DISPLAY 0.617021 (2310 3210);
PAINT ORANGE (2310 3210);
FORCEPROP 2 LASTPIN (2300 3150) $PN 165
J 0
(2310 3160);
DISPLAY 0.617021 (2310 3160);
PAINT ORANGE (2310 3160);
FORCEPROP 2 LASTPIN (2300 3100) $PN 167
J 0
(2310 3110);
DISPLAY 0.617021 (2310 3110);
PAINT ORANGE (2310 3110);
FORCEPROP 2 LASTPIN (2300 3050) $PN 169
J 0
(2310 3060);
DISPLAY 0.617021 (2310 3060);
PAINT ORANGE (2310 3060);
FORCEPROP 2 LASTPIN (2300 3000) $PN 171
J 0
(2310 3010);
DISPLAY 0.617021 (2310 3010);
PAINT ORANGE (2310 3010);
FORCEPROP 2 LASTPIN (2300 2950) $PN 173
J 0
(2310 2960);
DISPLAY 0.617021 (2310 2960);
PAINT ORANGE (2310 2960);
FORCEPROP 2 LASTPIN (2300 2900) $PN 176
J 0
(2310 2910);
DISPLAY 0.617021 (2310 2910);
PAINT ORANGE (2310 2910);
FORCEPROP 2 LASTPIN (2300 2850) $PN 178
J 0
(2310 2860);
DISPLAY 0.617021 (2310 2860);
PAINT ORANGE (2310 2860);
FORCEPROP 2 LASTPIN (2300 2800) $PN 180
J 0
(2310 2810);
DISPLAY 0.617021 (2310 2810);
PAINT ORANGE (2310 2810);
FORCEPROP 2 LASTPIN (2300 2750) $PN 182
J 0
(2310 2760);
DISPLAY 0.617021 (2310 2760);
PAINT ORANGE (2310 2760);
FORCEPROP 2 LASTPIN (2300 2700) $PN 184
J 0
(2310 2710);
DISPLAY 0.617021 (2310 2710);
PAINT ORANGE (2310 2710);
FORCEPROP 2 LASTPIN (2300 2650) $PN 187
J 0
(2310 2660);
DISPLAY 0.617021 (2310 2660);
PAINT ORANGE (2310 2660);
FORCEPROP 2 LASTPIN (2300 2600) $PN 189
J 0
(2310 2610);
DISPLAY 0.617021 (2310 2610);
PAINT ORANGE (2310 2610);
FORCEPROP 2 LASTPIN (2300 2550) $PN 191
J 0
(2310 2560);
DISPLAY 0.617021 (2310 2560);
PAINT ORANGE (2310 2560);
FORCEPROP 2 LASTPIN (2300 2500) $PN 193
J 0
(2310 2510);
DISPLAY 0.617021 (2310 2510);
PAINT ORANGE (2310 2510);
FORCEPROP 2 LASTPIN (2300 2450) $PN 195
J 0
(2310 2460);
DISPLAY 0.617021 (2310 2460);
PAINT ORANGE (2310 2460);
FORCEPROP 2 LASTPIN (2300 2400) $PN 198
J 0
(2310 2410);
DISPLAY 0.617021 (2310 2410);
PAINT ORANGE (2310 2410);
FORCEPROP 2 LASTPIN (2300 2350) $PN 200
J 0
(2310 2360);
DISPLAY 0.617021 (2310 2360);
PAINT ORANGE (2310 2360);
FORCEPROP 2 LASTPIN (2300 2300) $PN 202
J 0
(2310 2310);
DISPLAY 0.617021 (2310 2310);
PAINT ORANGE (2310 2310);
FORCEPROP 2 LASTPIN (2300 2250) $PN 239
J 0
(2310 2260);
DISPLAY 0.617021 (2310 2260);
PAINT ORANGE (2310 2260);
FORCEPROP 2 LASTPIN (2300 2200) $PN 241
J 0
(2310 2210);
DISPLAY 0.617021 (2310 2210);
PAINT ORANGE (2310 2210);
FORCEPROP 2 LASTPIN (2300 2150) $PN 243
J 0
(2310 2160);
DISPLAY 0.617021 (2310 2160);
PAINT ORANGE (2310 2160);
FORCEPROP 2 LASTPIN (2300 2100) $PN 246
J 0
(2310 2110);
DISPLAY 0.617021 (2310 2110);
PAINT ORANGE (2310 2110);
FORCEPROP 2 LASTPIN (2300 2050) $PN 248
J 0
(2310 2060);
DISPLAY 0.617021 (2310 2060);
PAINT ORANGE (2310 2060);
FORCEPROP 2 LASTPIN (2300 2000) $PN 250
J 0
(2310 2010);
DISPLAY 0.617021 (2310 2010);
PAINT ORANGE (2310 2010);
FORCEPROP 2 LASTPIN (2300 1950) $PN 252
J 0
(2310 1960);
DISPLAY 0.617021 (2310 1960);
PAINT ORANGE (2310 1960);
FORCEPROP 2 LASTPIN (2300 1900) $PN 254
J 0
(2310 1910);
DISPLAY 0.617021 (2310 1910);
PAINT ORANGE (2310 1910);
FORCEPROP 2 LASTPIN (2300 1850) $PN 257
J 0
(2310 1860);
DISPLAY 0.617021 (2310 1860);
PAINT ORANGE (2310 1860);
FORCEPROP 2 LASTPIN (2300 1800) $PN 259
J 0
(2310 1810);
DISPLAY 0.617021 (2310 1810);
PAINT ORANGE (2310 1810);
FORCEPROP 2 LASTPIN (2300 1750) $PN 261
J 0
(2310 1760);
DISPLAY 0.617021 (2310 1760);
PAINT ORANGE (2310 1760);
FORCEPROP 2 LASTPIN (2300 1700) $PN 263
J 0
(2310 1710);
DISPLAY 0.617021 (2310 1710);
PAINT ORANGE (2310 1710);
FORCEPROP 2 LASTPIN (2300 1650) $PN 265
J 0
(2310 1660);
DISPLAY 0.617021 (2310 1660);
PAINT ORANGE (2310 1660);
FORCEPROP 2 LASTPIN (2300 1600) $PN 268
J 0
(2310 1610);
DISPLAY 0.617021 (2310 1610);
PAINT ORANGE (2310 1610);
FORCEPROP 2 LASTPIN (2300 1550) $PN 270
J 0
(2310 1560);
DISPLAY 0.617021 (2310 1560);
PAINT ORANGE (2310 1560);
FORCEPROP 2 LASTPIN (2300 1500) $PN 272
J 0
(2310 1510);
DISPLAY 0.617021 (2310 1510);
PAINT ORANGE (2310 1510);
FORCEPROP 2 LASTPIN (2300 1450) $PN 274
J 0
(2310 1460);
DISPLAY 0.617021 (2310 1460);
PAINT ORANGE (2310 1460);
FORCEPROP 2 LASTPIN (2300 1400) $PN 276
J 0
(2310 1410);
DISPLAY 0.617021 (2310 1410);
PAINT ORANGE (2310 1410);
FORCEPROP 2 LASTPIN (2300 1350) $PN 279
J 0
(2310 1360);
DISPLAY 0.617021 (2310 1360);
PAINT ORANGE (2310 1360);
FORCEPROP 2 LASTPIN (2300 1300) $PN 281
J 0
(2310 1310);
DISPLAY 0.617021 (2310 1310);
PAINT ORANGE (2310 1310);
FORCEPROP 2 LASTPIN (2300 1250) $PN 283
J 0
(2310 1260);
DISPLAY 0.617021 (2310 1260);
PAINT ORANGE (2310 1260);
FORCEPROP 1 LAST PACK_TYPE PIP
J 0
(1350 3850);
PAINT SKYBLUE (1350 3850);
DISPLAY INVISIBLE (1350 3850);
FORCEPROP 2 LAST SEC_TYPE PIP
J 0
(1350 3850);
DISPLAY 1.021277 (1350 3850);
PAINT ORANGE (1350 3850);
DISPLAY INVISIBLE (1350 3850);
FORCEPROP 2 LAST CDS_LIB mstr_sconn
J 0
(1800 2400);
PAINT ORANGE (1800 2400);
DISPLAY INVISIBLE (1800 2400);
FORCEPROP 2 LAST BOM_COST DDR4_CH_M
J 0
(1800 2400);
PAINT ORANGE (1800 2400);
DISPLAY INVISIBLE (1800 2400);
FORCEPROP 2 LAST SEC 3
J 0
(1350 3850);
DISPLAY 0.680851 (1350 3850);
PAINT MONO (1350 3850);
DISPLAY INVISIBLE (1350 3850);
FORCEPROP 2 LAST CDS_LOCATION J9L1
J 0
(1350 3800);
DISPLAY 0.617021 (1350 3800);
PAINT AQUA (1350 3800);
DISPLAY INVISIBLE (1350 3800);
FORCEPROP 1 LAST PATH I25
J 0
(1800 3750);
PAINT GREEN (1800 3750);
DISPLAY INVISIBLE (1800 3750);
FORCEPROP 2 LAST ROOM DDR4_CH_M
J 0
(1800 2400);
PAINT ORANGE (1800 2400);
DISPLAY INVISIBLE (1800 2400);
FORCEADD GND..1
R 2
(1100 1100);
FORCEPROP 3 LASTPIN (1100 1150) SIG_NAME GND\g
J 0
(1110 1160);
DISPLAY 0.659574 (1110 1160);
PAINT MONO (1110 1160);
DISPLAY INVISIBLE (1110 1160);
FORCEPROP 1 LAST VOLTAGE 4V
J 0
(1100 1100);
PAINT SKYBLUE (1100 1100);
DISPLAY INVISIBLE (1100 1100);
FORCEPROP 1 LAST SIZE 1B
J 2
(1025 1050);
DISPLAY 1.170213 (1025 1050);
PAINT GREEN (1025 1050);
DISPLAY INVISIBLE (1025 1050);
FORCEPROP 2 LAST CDS_LIB mstr_symbols
J 0
(1100 1100);
DISPLAY 0.787234 (1100 1100);
PAINT MONO (1100 1100);
DISPLAY INVISIBLE (1100 1100);
FORCEPROP 2 LAST BOM_COST PROC
J 0
(1100 1105);
PAINT ORANGE (1100 1105);
DISPLAY INVISIBLE (1100 1105);
FORCEPROP 1 LAST BODY_TYPE PLUMBING
J 2
(1145 1057);
DISPLAY 0.340426 (1145 1057);
PAINT GREEN (1145 1057);
DISPLAY INVISIBLE (1145 1057);
FORCEPROP 1 LAST PATH I26
J 2
(1025 1100);
DISPLAY 0.936170 (1025 1100);
PAINT GREEN (1025 1100);
DISPLAY INVISIBLE (1025 1100);
FORCEPROP 2 LAST ROOM PROC
J 0
(1100 1105);
PAINT ORANGE (1100 1105);
DISPLAY INVISIBLE (1100 1105);
FORCEPROP 1 LAST HDL_POWER GND
J 2
(1100 1250);
DISPLAY 0.553191 (1100 1250);
PAINT GREEN (1100 1250);
DISPLAY INVISIBLE (1100 1250);
FORCEADD TAP..6
R 2
(700 5150);
FORCEPROP 3 LASTPIN (650 5150) SIG_NAME M_M_DQS_DP<17>
J 0
(660 5160);
DISPLAY 0.659574 (660 5160);
PAINT MONO (660 5160);
DISPLAY INVISIBLE (660 5160);
FORCEPROP 1 LASTPIN (650 5150) BN 17
J 2
(700 5160);
DISPLAY 0.617021 (700 5160);
PAINT PINK (700 5160);
FORCEPROP 2 LAST CDS_LIB mstr_standard
J 2
(700 5150);
DISPLAY 0.787234 (700 5150);
PAINT MONO (700 5150);
DISPLAY INVISIBLE (700 5150);
FORCEPROP 1 LAST BODY_TYPE PLUMBING
J 2
(700 5100);
DISPLAY 1.234043 (700 5100);
PAINT GREEN (700 5100);
DISPLAY INVISIBLE (700 5100);
FORCEPROP 1 LAST HDL_TAP TRUE
J 2
(375 5025);
DISPLAY 1.234043 (375 5025);
PAINT GREEN (375 5025);
DISPLAY INVISIBLE (375 5025);
FORCEPROP 1 LAST PATH I27
J 2
(700 5150);
DISPLAY 0.936170 (700 5150);
PAINT GREEN (700 5150);
DISPLAY INVISIBLE (700 5150);
FORCEADD TAP..6
R 2
(700 5050);
FORCEPROP 3 LASTPIN (650 5050) SIG_NAME M_M_DQS_DP<16>
J 0
(660 5060);
DISPLAY 0.659574 (660 5060);
PAINT MONO (660 5060);
DISPLAY INVISIBLE (660 5060);
FORCEPROP 1 LASTPIN (650 5050) BN 16
J 2
(700 5060);
DISPLAY 0.617021 (700 5060);
PAINT PINK (700 5060);
FORCEPROP 2 LAST CDS_LIB mstr_standard
J 0
(700 5050);
DISPLAY 0.787234 (700 5050);
PAINT MONO (700 5050);
DISPLAY INVISIBLE (700 5050);
FORCEPROP 1 LAST BODY_TYPE PLUMBING
J 2
(700 5000);
DISPLAY 1.234043 (700 5000);
PAINT GREEN (700 5000);
DISPLAY INVISIBLE (700 5000);
FORCEPROP 1 LAST HDL_TAP TRUE
J 2
(375 4925);
DISPLAY 1.234043 (375 4925);
PAINT GREEN (375 4925);
DISPLAY INVISIBLE (375 4925);
FORCEPROP 1 LAST PATH I28
J 2
(700 5050);
DISPLAY 0.936170 (700 5050);
PAINT GREEN (700 5050);
DISPLAY INVISIBLE (700 5050);
FORCEADD TAP..6
R 2
(700 4750);
FORCEPROP 3 LASTPIN (650 4750) SIG_NAME M_M_DQS_DP<13>
J 0
(660 4760);
DISPLAY 0.659574 (660 4760);
PAINT MONO (660 4760);
DISPLAY INVISIBLE (660 4760);
FORCEPROP 1 LASTPIN (650 4750) BN 13
J 2
(700 4760);
DISPLAY 0.617021 (700 4760);
PAINT PINK (700 4760);
FORCEPROP 2 LAST CDS_LIB mstr_standard
J 0
(700 4750);
DISPLAY 0.787234 (700 4750);
PAINT MONO (700 4750);
DISPLAY INVISIBLE (700 4750);
FORCEPROP 1 LAST BODY_TYPE PLUMBING
J 2
(700 4700);
DISPLAY 1.234043 (700 4700);
PAINT GREEN (700 4700);
DISPLAY INVISIBLE (700 4700);
FORCEPROP 1 LAST HDL_TAP TRUE
J 2
(375 4625);
DISPLAY 1.234043 (375 4625);
PAINT GREEN (375 4625);
DISPLAY INVISIBLE (375 4625);
FORCEPROP 1 LAST PATH I29
J 2
(700 4750);
DISPLAY 0.936170 (700 4750);
PAINT GREEN (700 4750);
DISPLAY INVISIBLE (700 4750);
FORCEADD TAP..6
R 2
(900 5100);
FORCEPROP 3 LASTPIN (850 5100) SIG_NAME M_M_DQS_DN<17>
J 0
(860 5110);
DISPLAY 0.659574 (860 5110);
PAINT MONO (860 5110);
DISPLAY INVISIBLE (860 5110);
FORCEPROP 1 LASTPIN (850 5100) BN 17
J 2
(900 5110);
DISPLAY 0.617021 (900 5110);
PAINT PINK (900 5110);
FORCEPROP 2 LAST CDS_LIB mstr_standard
J 2
(900 5100);
DISPLAY 0.787234 (900 5100);
PAINT MONO (900 5100);
DISPLAY INVISIBLE (900 5100);
FORCEPROP 1 LAST BODY_TYPE PLUMBING
J 2
(900 5050);
DISPLAY 1.234043 (900 5050);
PAINT GREEN (900 5050);
DISPLAY INVISIBLE (900 5050);
FORCEPROP 1 LAST HDL_TAP TRUE
J 2
(575 4975);
DISPLAY 1.234043 (575 4975);
PAINT GREEN (575 4975);
DISPLAY INVISIBLE (575 4975);
FORCEPROP 1 LAST PATH I3
J 2
(900 5100);
DISPLAY 0.936170 (900 5100);
PAINT GREEN (900 5100);
DISPLAY INVISIBLE (900 5100);
FORCEADD TAP..6
R 2
(700 4650);
FORCEPROP 3 LASTPIN (650 4650) SIG_NAME M_M_DQS_DP<12>
J 0
(660 4660);
DISPLAY 0.659574 (660 4660);
PAINT MONO (660 4660);
DISPLAY INVISIBLE (660 4660);
FORCEPROP 1 LASTPIN (650 4650) BN 12
J 2
(700 4660);
DISPLAY 0.617021 (700 4660);
PAINT PINK (700 4660);
FORCEPROP 2 LAST CDS_LIB mstr_standard
J 0
(700 4650);
DISPLAY 0.787234 (700 4650);
PAINT MONO (700 4650);
DISPLAY INVISIBLE (700 4650);
FORCEPROP 1 LAST BODY_TYPE PLUMBING
J 2
(700 4600);
DISPLAY 1.234043 (700 4600);
PAINT GREEN (700 4600);
DISPLAY INVISIBLE (700 4600);
FORCEPROP 1 LAST HDL_TAP TRUE
J 2
(375 4525);
DISPLAY 1.234043 (375 4525);
PAINT GREEN (375 4525);
DISPLAY INVISIBLE (375 4525);
FORCEPROP 1 LAST PATH I30
J 2
(700 4650);
DISPLAY 0.936170 (700 4650);
PAINT GREEN (700 4650);
DISPLAY INVISIBLE (700 4650);
FORCEADD TAP..6
R 2
(700 4550);
FORCEPROP 3 LASTPIN (650 4550) SIG_NAME M_M_DQS_DP<11>
J 0
(660 4560);
DISPLAY 0.659574 (660 4560);
PAINT MONO (660 4560);
DISPLAY INVISIBLE (660 4560);
FORCEPROP 1 LASTPIN (650 4550) BN 11
J 2
(700 4560);
DISPLAY 0.617021 (700 4560);
PAINT PINK (700 4560);
FORCEPROP 2 LAST CDS_LIB mstr_standard
J 0
(700 4550);
DISPLAY 0.787234 (700 4550);
PAINT MONO (700 4550);
DISPLAY INVISIBLE (700 4550);
FORCEPROP 1 LAST BODY_TYPE PLUMBING
J 2
(700 4500);
DISPLAY 1.234043 (700 4500);
PAINT GREEN (700 4500);
DISPLAY INVISIBLE (700 4500);
FORCEPROP 1 LAST HDL_TAP TRUE
J 2
(375 4425);
DISPLAY 1.234043 (375 4425);
PAINT GREEN (375 4425);
DISPLAY INVISIBLE (375 4425);
FORCEPROP 1 LAST PATH I31
J 2
(700 4550);
DISPLAY 0.936170 (700 4550);
PAINT GREEN (700 4550);
DISPLAY INVISIBLE (700 4550);
FORCEADD TAP..6
R 2
(700 4950);
FORCEPROP 3 LASTPIN (650 4950) SIG_NAME M_M_DQS_DP<15>
J 0
(660 4960);
DISPLAY 0.659574 (660 4960);
PAINT MONO (660 4960);
DISPLAY INVISIBLE (660 4960);
FORCEPROP 1 LASTPIN (650 4950) BN 15
J 2
(700 4960);
DISPLAY 0.617021 (700 4960);
PAINT PINK (700 4960);
FORCEPROP 2 LAST CDS_LIB mstr_standard
J 0
(700 4950);
DISPLAY 0.787234 (700 4950);
PAINT MONO (700 4950);
DISPLAY INVISIBLE (700 4950);
FORCEPROP 1 LAST BODY_TYPE PLUMBING
J 2
(700 4900);
DISPLAY 1.234043 (700 4900);
PAINT GREEN (700 4900);
DISPLAY INVISIBLE (700 4900);
FORCEPROP 1 LAST HDL_TAP TRUE
J 2
(375 4825);
DISPLAY 1.234043 (375 4825);
PAINT GREEN (375 4825);
DISPLAY INVISIBLE (375 4825);
FORCEPROP 1 LAST PATH I32
J 2
(700 4950);
DISPLAY 0.936170 (700 4950);
PAINT GREEN (700 4950);
DISPLAY INVISIBLE (700 4950);
FORCEADD TAP..6
R 2
(700 4850);
FORCEPROP 3 LASTPIN (650 4850) SIG_NAME M_M_DQS_DP<14>
J 0
(660 4860);
DISPLAY 0.659574 (660 4860);
PAINT MONO (660 4860);
DISPLAY INVISIBLE (660 4860);
FORCEPROP 1 LASTPIN (650 4850) BN 14
J 2
(700 4860);
DISPLAY 0.617021 (700 4860);
PAINT PINK (700 4860);
FORCEPROP 2 LAST CDS_LIB mstr_standard
J 0
(700 4850);
DISPLAY 0.787234 (700 4850);
PAINT MONO (700 4850);
DISPLAY INVISIBLE (700 4850);
FORCEPROP 1 LAST BODY_TYPE PLUMBING
J 2
(700 4800);
DISPLAY 1.234043 (700 4800);
PAINT GREEN (700 4800);
DISPLAY INVISIBLE (700 4800);
FORCEPROP 1 LAST HDL_TAP TRUE
J 2
(375 4725);
DISPLAY 1.234043 (375 4725);
PAINT GREEN (375 4725);
DISPLAY INVISIBLE (375 4725);
FORCEPROP 1 LAST PATH I33
J 2
(700 4850);
DISPLAY 0.936170 (700 4850);
PAINT GREEN (700 4850);
DISPLAY INVISIBLE (700 4850);
FORCEADD OFFPAGE..3
(-1150 4800);
FORCEPROP 2 LAST $XR0 62 
J 0
(-936 4800);
DISPLAY 0.638298 (-936 4800);
PAINT MONO (-936 4800);
FORCEPROP 2 LAST $XR1 87 
J 0
(-846 4800);
DISPLAY 0.638298 (-846 4800);
PAINT MONO (-846 4800);
FORCEPROP 2 LAST CDS_LIB mstr_standard
J 0
(-1150 4800);
DISPLAY 0.787234 (-1150 4800);
PAINT MONO (-1150 4800);
DISPLAY INVISIBLE (-1150 4800);
FORCEPROP 1 LAST OFFPAGE TRUE
J 0
(-825 4675);
DISPLAY 0.936170 (-825 4675);
PAINT GREEN (-825 4675);
DISPLAY INVISIBLE (-825 4675);
FORCEPROP 1 LAST COMMENT_BODY TRUE
J 0
(-1200 4700);
DISPLAY 0.936170 (-1200 4700);
PAINT GREEN (-1200 4700);
DISPLAY INVISIBLE (-1200 4700);
FORCEPROP 2 LAST PATH I34
J 0
(-950 4875);
DISPLAY 0.787234 (-950 4875);
PAINT MONO (-950 4875);
DISPLAY INVISIBLE (-950 4875);
FORCEADD TAP..6
R 2
(-1700 4550);
FORCEPROP 3 LASTPIN (-1750 4550) SIG_NAME M_M_DQ<59>
J 0
(-1740 4560);
DISPLAY 0.659574 (-1740 4560);
PAINT MONO (-1740 4560);
DISPLAY INVISIBLE (-1740 4560);
FORCEPROP 1 LASTPIN (-1750 4550) BN 59
J 2
(-1700 4560);
DISPLAY 0.617021 (-1700 4560);
PAINT PINK (-1700 4560);
FORCEPROP 2 LAST CDS_LIB mstr_standard
J 2
(-1700 4550);
DISPLAY 0.787234 (-1700 4550);
PAINT MONO (-1700 4550);
DISPLAY INVISIBLE (-1700 4550);
FORCEPROP 1 LAST BODY_TYPE PLUMBING
J 2
(-1700 4500);
DISPLAY 1.234043 (-1700 4500);
PAINT GREEN (-1700 4500);
DISPLAY INVISIBLE (-1700 4500);
FORCEPROP 1 LAST HDL_TAP TRUE
J 2
(-2025 4425);
DISPLAY 1.234043 (-2025 4425);
PAINT GREEN (-2025 4425);
DISPLAY INVISIBLE (-2025 4425);
FORCEPROP 1 LAST PATH I35
J 2
(-1700 4550);
DISPLAY 0.936170 (-1700 4550);
PAINT GREEN (-1700 4550);
DISPLAY INVISIBLE (-1700 4550);
FORCEADD TAP..6
R 2
(-1700 4750);
FORCEPROP 3 LASTPIN (-1750 4750) SIG_NAME M_M_DQ<63>
J 0
(-1740 4760);
DISPLAY 0.659574 (-1740 4760);
PAINT MONO (-1740 4760);
DISPLAY INVISIBLE (-1740 4760);
FORCEPROP 1 LASTPIN (-1750 4750) BN 63
J 2
(-1700 4760);
DISPLAY 0.617021 (-1700 4760);
PAINT PINK (-1700 4760);
FORCEPROP 2 LAST CDS_LIB mstr_standard
J 2
(-1700 4750);
DISPLAY 0.787234 (-1700 4750);
PAINT MONO (-1700 4750);
DISPLAY INVISIBLE (-1700 4750);
FORCEPROP 1 LAST BODY_TYPE PLUMBING
J 2
(-1700 4700);
DISPLAY 1.234043 (-1700 4700);
PAINT GREEN (-1700 4700);
DISPLAY INVISIBLE (-1700 4700);
FORCEPROP 1 LAST HDL_TAP TRUE
J 2
(-2025 4625);
DISPLAY 1.234043 (-2025 4625);
PAINT GREEN (-2025 4625);
DISPLAY INVISIBLE (-2025 4625);
FORCEPROP 1 LAST PATH I36
J 2
(-1700 4750);
DISPLAY 0.936170 (-1700 4750);
PAINT GREEN (-1700 4750);
DISPLAY INVISIBLE (-1700 4750);
FORCEADD TAP..6
R 2
(-1700 4700);
FORCEPROP 3 LASTPIN (-1750 4700) SIG_NAME M_M_DQ<62>
J 0
(-1740 4710);
DISPLAY 0.659574 (-1740 4710);
PAINT MONO (-1740 4710);
DISPLAY INVISIBLE (-1740 4710);
FORCEPROP 1 LASTPIN (-1750 4700) BN 62
J 2
(-1700 4710);
DISPLAY 0.617021 (-1700 4710);
PAINT PINK (-1700 4710);
FORCEPROP 2 LAST CDS_LIB mstr_standard
J 2
(-1700 4700);
DISPLAY 0.787234 (-1700 4700);
PAINT MONO (-1700 4700);
DISPLAY INVISIBLE (-1700 4700);
FORCEPROP 1 LAST BODY_TYPE PLUMBING
J 2
(-1700 4650);
DISPLAY 1.234043 (-1700 4650);
PAINT GREEN (-1700 4650);
DISPLAY INVISIBLE (-1700 4650);
FORCEPROP 1 LAST HDL_TAP TRUE
J 2
(-2025 4575);
DISPLAY 1.234043 (-2025 4575);
PAINT GREEN (-2025 4575);
DISPLAY INVISIBLE (-2025 4575);
FORCEPROP 1 LAST PATH I37
J 2
(-1700 4700);
DISPLAY 0.936170 (-1700 4700);
PAINT GREEN (-1700 4700);
DISPLAY INVISIBLE (-1700 4700);
FORCEADD TAP..6
R 2
(-1700 4650);
FORCEPROP 3 LASTPIN (-1750 4650) SIG_NAME M_M_DQ<61>
J 0
(-1740 4660);
DISPLAY 0.659574 (-1740 4660);
PAINT MONO (-1740 4660);
DISPLAY INVISIBLE (-1740 4660);
FORCEPROP 1 LASTPIN (-1750 4650) BN 61
J 2
(-1700 4660);
DISPLAY 0.617021 (-1700 4660);
PAINT PINK (-1700 4660);
FORCEPROP 2 LAST CDS_LIB mstr_standard
J 2
(-1700 4650);
DISPLAY 0.787234 (-1700 4650);
PAINT MONO (-1700 4650);
DISPLAY INVISIBLE (-1700 4650);
FORCEPROP 1 LAST BODY_TYPE PLUMBING
J 2
(-1700 4600);
DISPLAY 1.234043 (-1700 4600);
PAINT GREEN (-1700 4600);
DISPLAY INVISIBLE (-1700 4600);
FORCEPROP 1 LAST HDL_TAP TRUE
J 2
(-2025 4525);
DISPLAY 1.234043 (-2025 4525);
PAINT GREEN (-2025 4525);
DISPLAY INVISIBLE (-2025 4525);
FORCEPROP 1 LAST PATH I38
J 2
(-1700 4650);
DISPLAY 0.936170 (-1700 4650);
PAINT GREEN (-1700 4650);
DISPLAY INVISIBLE (-1700 4650);
FORCEADD TAP..6
R 2
(-1700 4600);
FORCEPROP 3 LASTPIN (-1750 4600) SIG_NAME M_M_DQ<60>
J 0
(-1740 4610);
DISPLAY 0.659574 (-1740 4610);
PAINT MONO (-1740 4610);
DISPLAY INVISIBLE (-1740 4610);
FORCEPROP 1 LASTPIN (-1750 4600) BN 60
J 2
(-1700 4610);
DISPLAY 0.617021 (-1700 4610);
PAINT PINK (-1700 4610);
FORCEPROP 2 LAST CDS_LIB mstr_standard
J 2
(-1700 4600);
DISPLAY 0.787234 (-1700 4600);
PAINT MONO (-1700 4600);
DISPLAY INVISIBLE (-1700 4600);
FORCEPROP 1 LAST BODY_TYPE PLUMBING
J 2
(-1700 4550);
DISPLAY 1.234043 (-1700 4550);
PAINT GREEN (-1700 4550);
DISPLAY INVISIBLE (-1700 4550);
FORCEPROP 1 LAST HDL_TAP TRUE
J 2
(-2025 4475);
DISPLAY 1.234043 (-2025 4475);
PAINT GREEN (-2025 4475);
DISPLAY INVISIBLE (-2025 4475);
FORCEPROP 1 LAST PATH I39
J 2
(-1700 4600);
DISPLAY 0.936170 (-1700 4600);
PAINT GREEN (-1700 4600);
DISPLAY INVISIBLE (-1700 4600);
FORCEADD TAP..6
R 2
(900 5000);
FORCEPROP 3 LASTPIN (850 5000) SIG_NAME M_M_DQS_DN<16>
J 0
(860 5010);
DISPLAY 0.659574 (860 5010);
PAINT MONO (860 5010);
DISPLAY INVISIBLE (860 5010);
FORCEPROP 1 LASTPIN (850 5000) BN 16
J 2
(900 5010);
DISPLAY 0.617021 (900 5010);
PAINT PINK (900 5010);
FORCEPROP 2 LAST CDS_LIB mstr_standard
J 0
(900 5000);
DISPLAY 0.787234 (900 5000);
PAINT MONO (900 5000);
DISPLAY INVISIBLE (900 5000);
FORCEPROP 1 LAST BODY_TYPE PLUMBING
J 2
(900 4950);
DISPLAY 1.234043 (900 4950);
PAINT GREEN (900 4950);
DISPLAY INVISIBLE (900 4950);
FORCEPROP 1 LAST HDL_TAP TRUE
J 2
(575 4875);
DISPLAY 1.234043 (575 4875);
PAINT GREEN (575 4875);
DISPLAY INVISIBLE (575 4875);
FORCEPROP 1 LAST PATH I4
J 2
(900 5000);
DISPLAY 0.936170 (900 5000);
PAINT GREEN (900 5000);
DISPLAY INVISIBLE (900 5000);
FORCEADD TAP..6
R 2
(-1700 4300);
FORCEPROP 3 LASTPIN (-1750 4300) SIG_NAME M_M_DQ<54>
J 0
(-1740 4310);
DISPLAY 0.659574 (-1740 4310);
PAINT MONO (-1740 4310);
DISPLAY INVISIBLE (-1740 4310);
FORCEPROP 1 LASTPIN (-1750 4300) BN 54
J 2
(-1700 4310);
DISPLAY 0.617021 (-1700 4310);
PAINT PINK (-1700 4310);
FORCEPROP 2 LAST CDS_LIB mstr_standard
J 2
(-1700 4300);
DISPLAY 0.787234 (-1700 4300);
PAINT MONO (-1700 4300);
DISPLAY INVISIBLE (-1700 4300);
FORCEPROP 1 LAST BODY_TYPE PLUMBING
J 2
(-1700 4250);
DISPLAY 1.234043 (-1700 4250);
PAINT GREEN (-1700 4250);
DISPLAY INVISIBLE (-1700 4250);
FORCEPROP 1 LAST HDL_TAP TRUE
J 2
(-2025 4175);
DISPLAY 1.234043 (-2025 4175);
PAINT GREEN (-2025 4175);
DISPLAY INVISIBLE (-2025 4175);
FORCEPROP 1 LAST PATH I40
J 2
(-1700 4300);
DISPLAY 0.936170 (-1700 4300);
PAINT GREEN (-1700 4300);
DISPLAY INVISIBLE (-1700 4300);
FORCEADD TAP..6
R 2
(-1700 4450);
FORCEPROP 3 LASTPIN (-1750 4450) SIG_NAME M_M_DQ<57>
J 0
(-1740 4460);
DISPLAY 0.659574 (-1740 4460);
PAINT MONO (-1740 4460);
DISPLAY INVISIBLE (-1740 4460);
FORCEPROP 1 LASTPIN (-1750 4450) BN 57
J 2
(-1700 4460);
DISPLAY 0.617021 (-1700 4460);
PAINT PINK (-1700 4460);
FORCEPROP 2 LAST CDS_LIB mstr_standard
J 2
(-1700 4450);
DISPLAY 0.787234 (-1700 4450);
PAINT MONO (-1700 4450);
DISPLAY INVISIBLE (-1700 4450);
FORCEPROP 1 LAST BODY_TYPE PLUMBING
J 2
(-1700 4400);
DISPLAY 1.234043 (-1700 4400);
PAINT GREEN (-1700 4400);
DISPLAY INVISIBLE (-1700 4400);
FORCEPROP 1 LAST HDL_TAP TRUE
J 2
(-2025 4325);
DISPLAY 1.234043 (-2025 4325);
PAINT GREEN (-2025 4325);
DISPLAY INVISIBLE (-2025 4325);
FORCEPROP 1 LAST PATH I41
J 2
(-1700 4450);
DISPLAY 0.936170 (-1700 4450);
PAINT GREEN (-1700 4450);
DISPLAY INVISIBLE (-1700 4450);
FORCEADD TAP..6
R 2
(-1700 4500);
FORCEPROP 3 LASTPIN (-1750 4500) SIG_NAME M_M_DQ<58>
J 0
(-1740 4510);
DISPLAY 0.659574 (-1740 4510);
PAINT MONO (-1740 4510);
DISPLAY INVISIBLE (-1740 4510);
FORCEPROP 1 LASTPIN (-1750 4500) BN 58
J 2
(-1700 4510);
DISPLAY 0.617021 (-1700 4510);
PAINT PINK (-1700 4510);
FORCEPROP 2 LAST CDS_LIB mstr_standard
J 2
(-1700 4500);
DISPLAY 0.787234 (-1700 4500);
PAINT MONO (-1700 4500);
DISPLAY INVISIBLE (-1700 4500);
FORCEPROP 1 LAST BODY_TYPE PLUMBING
J 2
(-1700 4450);
DISPLAY 1.234043 (-1700 4450);
PAINT GREEN (-1700 4450);
DISPLAY INVISIBLE (-1700 4450);
FORCEPROP 1 LAST HDL_TAP TRUE
J 2
(-2025 4375);
DISPLAY 1.234043 (-2025 4375);
PAINT GREEN (-2025 4375);
DISPLAY INVISIBLE (-2025 4375);
FORCEPROP 1 LAST PATH I42
J 2
(-1700 4500);
DISPLAY 0.936170 (-1700 4500);
PAINT GREEN (-1700 4500);
DISPLAY INVISIBLE (-1700 4500);
FORCEADD TAP..6
R 2
(-1700 4350);
FORCEPROP 3 LASTPIN (-1750 4350) SIG_NAME M_M_DQ<55>
J 0
(-1740 4360);
DISPLAY 0.659574 (-1740 4360);
PAINT MONO (-1740 4360);
DISPLAY INVISIBLE (-1740 4360);
FORCEPROP 1 LASTPIN (-1750 4350) BN 55
J 2
(-1700 4360);
DISPLAY 0.617021 (-1700 4360);
PAINT PINK (-1700 4360);
FORCEPROP 2 LAST CDS_LIB mstr_standard
J 2
(-1700 4350);
DISPLAY 0.787234 (-1700 4350);
PAINT MONO (-1700 4350);
DISPLAY INVISIBLE (-1700 4350);
FORCEPROP 1 LAST BODY_TYPE PLUMBING
J 2
(-1700 4300);
DISPLAY 1.234043 (-1700 4300);
PAINT GREEN (-1700 4300);
DISPLAY INVISIBLE (-1700 4300);
FORCEPROP 1 LAST HDL_TAP TRUE
J 2
(-2025 4225);
DISPLAY 1.234043 (-2025 4225);
PAINT GREEN (-2025 4225);
DISPLAY INVISIBLE (-2025 4225);
FORCEPROP 1 LAST PATH I43
J 2
(-1700 4350);
DISPLAY 0.936170 (-1700 4350);
PAINT GREEN (-1700 4350);
DISPLAY INVISIBLE (-1700 4350);
FORCEADD TAP..6
R 2
(-1700 4400);
FORCEPROP 3 LASTPIN (-1750 4400) SIG_NAME M_M_DQ<56>
J 0
(-1740 4410);
DISPLAY 0.659574 (-1740 4410);
PAINT MONO (-1740 4410);
DISPLAY INVISIBLE (-1740 4410);
FORCEPROP 1 LASTPIN (-1750 4400) BN 56
J 2
(-1700 4410);
DISPLAY 0.617021 (-1700 4410);
PAINT PINK (-1700 4410);
FORCEPROP 2 LAST CDS_LIB mstr_standard
J 2
(-1700 4400);
DISPLAY 0.787234 (-1700 4400);
PAINT MONO (-1700 4400);
DISPLAY INVISIBLE (-1700 4400);
FORCEPROP 1 LAST BODY_TYPE PLUMBING
J 2
(-1700 4350);
DISPLAY 1.234043 (-1700 4350);
PAINT GREEN (-1700 4350);
DISPLAY INVISIBLE (-1700 4350);
FORCEPROP 1 LAST HDL_TAP TRUE
J 2
(-2025 4275);
DISPLAY 1.234043 (-2025 4275);
PAINT GREEN (-2025 4275);
DISPLAY INVISIBLE (-2025 4275);
FORCEPROP 1 LAST PATH I44
J 2
(-1700 4400);
DISPLAY 0.936170 (-1700 4400);
PAINT GREEN (-1700 4400);
DISPLAY INVISIBLE (-1700 4400);
FORCEADD TAP..6
R 2
(-1700 4050);
FORCEPROP 3 LASTPIN (-1750 4050) SIG_NAME M_M_DQ<49>
J 0
(-1740 4060);
DISPLAY 0.659574 (-1740 4060);
PAINT MONO (-1740 4060);
DISPLAY INVISIBLE (-1740 4060);
FORCEPROP 1 LASTPIN (-1750 4050) BN 49
J 2
(-1700 4060);
DISPLAY 0.617021 (-1700 4060);
PAINT PINK (-1700 4060);
FORCEPROP 2 LAST CDS_LIB mstr_standard
J 2
(-1700 4050);
DISPLAY 0.787234 (-1700 4050);
PAINT MONO (-1700 4050);
DISPLAY INVISIBLE (-1700 4050);
FORCEPROP 1 LAST BODY_TYPE PLUMBING
J 2
(-1700 4000);
DISPLAY 1.234043 (-1700 4000);
PAINT GREEN (-1700 4000);
DISPLAY INVISIBLE (-1700 4000);
FORCEPROP 1 LAST HDL_TAP TRUE
J 2
(-2025 3925);
DISPLAY 1.234043 (-2025 3925);
PAINT GREEN (-2025 3925);
DISPLAY INVISIBLE (-2025 3925);
FORCEPROP 1 LAST PATH I45
J 2
(-1700 4050);
DISPLAY 0.936170 (-1700 4050);
PAINT GREEN (-1700 4050);
DISPLAY INVISIBLE (-1700 4050);
FORCEADD TAP..6
R 2
(-1700 4250);
FORCEPROP 3 LASTPIN (-1750 4250) SIG_NAME M_M_DQ<53>
J 0
(-1740 4260);
DISPLAY 0.659574 (-1740 4260);
PAINT MONO (-1740 4260);
DISPLAY INVISIBLE (-1740 4260);
FORCEPROP 1 LASTPIN (-1750 4250) BN 53
J 2
(-1700 4260);
DISPLAY 0.617021 (-1700 4260);
PAINT PINK (-1700 4260);
FORCEPROP 2 LAST CDS_LIB mstr_standard
J 2
(-1700 4250);
DISPLAY 0.787234 (-1700 4250);
PAINT MONO (-1700 4250);
DISPLAY INVISIBLE (-1700 4250);
FORCEPROP 1 LAST BODY_TYPE PLUMBING
J 2
(-1700 4200);
DISPLAY 1.234043 (-1700 4200);
PAINT GREEN (-1700 4200);
DISPLAY INVISIBLE (-1700 4200);
FORCEPROP 1 LAST HDL_TAP TRUE
J 2
(-2025 4125);
DISPLAY 1.234043 (-2025 4125);
PAINT GREEN (-2025 4125);
DISPLAY INVISIBLE (-2025 4125);
FORCEPROP 1 LAST PATH I46
J 2
(-1700 4250);
DISPLAY 0.936170 (-1700 4250);
PAINT GREEN (-1700 4250);
DISPLAY INVISIBLE (-1700 4250);
FORCEADD TAP..6
R 2
(-1700 4200);
FORCEPROP 3 LASTPIN (-1750 4200) SIG_NAME M_M_DQ<52>
J 0
(-1740 4210);
DISPLAY 0.659574 (-1740 4210);
PAINT MONO (-1740 4210);
DISPLAY INVISIBLE (-1740 4210);
FORCEPROP 1 LASTPIN (-1750 4200) BN 52
J 2
(-1700 4210);
DISPLAY 0.617021 (-1700 4210);
PAINT PINK (-1700 4210);
FORCEPROP 2 LAST CDS_LIB mstr_standard
J 2
(-1700 4200);
DISPLAY 0.787234 (-1700 4200);
PAINT MONO (-1700 4200);
DISPLAY INVISIBLE (-1700 4200);
FORCEPROP 1 LAST BODY_TYPE PLUMBING
J 2
(-1700 4150);
DISPLAY 1.234043 (-1700 4150);
PAINT GREEN (-1700 4150);
DISPLAY INVISIBLE (-1700 4150);
FORCEPROP 1 LAST HDL_TAP TRUE
J 2
(-2025 4075);
DISPLAY 1.234043 (-2025 4075);
PAINT GREEN (-2025 4075);
DISPLAY INVISIBLE (-2025 4075);
FORCEPROP 1 LAST PATH I47
J 2
(-1700 4200);
DISPLAY 0.936170 (-1700 4200);
PAINT GREEN (-1700 4200);
DISPLAY INVISIBLE (-1700 4200);
FORCEADD TAP..6
R 2
(-1700 4100);
FORCEPROP 3 LASTPIN (-1750 4100) SIG_NAME M_M_DQ<50>
J 0
(-1740 4110);
DISPLAY 0.659574 (-1740 4110);
PAINT MONO (-1740 4110);
DISPLAY INVISIBLE (-1740 4110);
FORCEPROP 1 LASTPIN (-1750 4100) BN 50
J 2
(-1700 4110);
DISPLAY 0.617021 (-1700 4110);
PAINT PINK (-1700 4110);
FORCEPROP 2 LAST CDS_LIB mstr_standard
J 2
(-1700 4100);
DISPLAY 0.787234 (-1700 4100);
PAINT MONO (-1700 4100);
DISPLAY INVISIBLE (-1700 4100);
FORCEPROP 1 LAST BODY_TYPE PLUMBING
J 2
(-1700 4050);
DISPLAY 1.234043 (-1700 4050);
PAINT GREEN (-1700 4050);
DISPLAY INVISIBLE (-1700 4050);
FORCEPROP 1 LAST HDL_TAP TRUE
J 2
(-2025 3975);
DISPLAY 1.234043 (-2025 3975);
PAINT GREEN (-2025 3975);
DISPLAY INVISIBLE (-2025 3975);
FORCEPROP 1 LAST PATH I48
J 2
(-1700 4100);
DISPLAY 0.936170 (-1700 4100);
PAINT GREEN (-1700 4100);
DISPLAY INVISIBLE (-1700 4100);
FORCEADD TAP..6
R 2
(-1700 4150);
FORCEPROP 3 LASTPIN (-1750 4150) SIG_NAME M_M_DQ<51>
J 0
(-1740 4160);
DISPLAY 0.659574 (-1740 4160);
PAINT MONO (-1740 4160);
DISPLAY INVISIBLE (-1740 4160);
FORCEPROP 1 LASTPIN (-1750 4150) BN 51
J 2
(-1700 4160);
DISPLAY 0.617021 (-1700 4160);
PAINT PINK (-1700 4160);
FORCEPROP 2 LAST CDS_LIB mstr_standard
J 2
(-1700 4150);
DISPLAY 0.787234 (-1700 4150);
PAINT MONO (-1700 4150);
DISPLAY INVISIBLE (-1700 4150);
FORCEPROP 1 LAST BODY_TYPE PLUMBING
J 2
(-1700 4100);
DISPLAY 1.234043 (-1700 4100);
PAINT GREEN (-1700 4100);
DISPLAY INVISIBLE (-1700 4100);
FORCEPROP 1 LAST HDL_TAP TRUE
J 2
(-2025 4025);
DISPLAY 1.234043 (-2025 4025);
PAINT GREEN (-2025 4025);
DISPLAY INVISIBLE (-2025 4025);
FORCEPROP 1 LAST PATH I49
J 2
(-1700 4150);
DISPLAY 0.936170 (-1700 4150);
PAINT GREEN (-1700 4150);
DISPLAY INVISIBLE (-1700 4150);
FORCEADD TAP..6
R 2
(900 4900);
FORCEPROP 3 LASTPIN (850 4900) SIG_NAME M_M_DQS_DN<15>
J 0
(860 4910);
DISPLAY 0.659574 (860 4910);
PAINT MONO (860 4910);
DISPLAY INVISIBLE (860 4910);
FORCEPROP 1 LASTPIN (850 4900) BN 15
J 2
(900 4910);
DISPLAY 0.617021 (900 4910);
PAINT PINK (900 4910);
FORCEPROP 2 LAST CDS_LIB mstr_standard
J 0
(900 4900);
DISPLAY 0.787234 (900 4900);
PAINT MONO (900 4900);
DISPLAY INVISIBLE (900 4900);
FORCEPROP 1 LAST BODY_TYPE PLUMBING
J 2
(900 4850);
DISPLAY 1.234043 (900 4850);
PAINT GREEN (900 4850);
DISPLAY INVISIBLE (900 4850);
FORCEPROP 1 LAST HDL_TAP TRUE
J 2
(575 4775);
DISPLAY 1.234043 (575 4775);
PAINT GREEN (575 4775);
DISPLAY INVISIBLE (575 4775);
FORCEPROP 1 LAST PATH I5
J 2
(900 4900);
DISPLAY 0.936170 (900 4900);
PAINT GREEN (900 4900);
DISPLAY INVISIBLE (900 4900);
FORCEADD TAP..6
R 2
(-1700 3950);
FORCEPROP 3 LASTPIN (-1750 3950) SIG_NAME M_M_DQ<47>
J 0
(-1740 3960);
DISPLAY 0.659574 (-1740 3960);
PAINT MONO (-1740 3960);
DISPLAY INVISIBLE (-1740 3960);
FORCEPROP 1 LASTPIN (-1750 3950) BN 47
J 2
(-1700 3960);
DISPLAY 0.617021 (-1700 3960);
PAINT PINK (-1700 3960);
FORCEPROP 2 LAST CDS_LIB mstr_standard
J 2
(-1700 3950);
DISPLAY 0.787234 (-1700 3950);
PAINT MONO (-1700 3950);
DISPLAY INVISIBLE (-1700 3950);
FORCEPROP 1 LAST BODY_TYPE PLUMBING
J 2
(-1700 3900);
DISPLAY 1.234043 (-1700 3900);
PAINT GREEN (-1700 3900);
DISPLAY INVISIBLE (-1700 3900);
FORCEPROP 1 LAST HDL_TAP TRUE
J 2
(-2025 3825);
DISPLAY 1.234043 (-2025 3825);
PAINT GREEN (-2025 3825);
DISPLAY INVISIBLE (-2025 3825);
FORCEPROP 1 LAST PATH I50
J 2
(-1700 3950);
DISPLAY 0.936170 (-1700 3950);
PAINT GREEN (-1700 3950);
DISPLAY INVISIBLE (-1700 3950);
FORCEADD TAP..6
R 2
(-1700 4000);
FORCEPROP 3 LASTPIN (-1750 4000) SIG_NAME M_M_DQ<48>
J 0
(-1740 4010);
DISPLAY 0.659574 (-1740 4010);
PAINT MONO (-1740 4010);
DISPLAY INVISIBLE (-1740 4010);
FORCEPROP 1 LASTPIN (-1750 4000) BN 48
J 2
(-1700 4010);
DISPLAY 0.617021 (-1700 4010);
PAINT PINK (-1700 4010);
FORCEPROP 2 LAST CDS_LIB mstr_standard
J 2
(-1700 4000);
DISPLAY 0.787234 (-1700 4000);
PAINT MONO (-1700 4000);
DISPLAY INVISIBLE (-1700 4000);
FORCEPROP 1 LAST BODY_TYPE PLUMBING
J 2
(-1700 3950);
DISPLAY 1.234043 (-1700 3950);
PAINT GREEN (-1700 3950);
DISPLAY INVISIBLE (-1700 3950);
FORCEPROP 1 LAST HDL_TAP TRUE
J 2
(-2025 3875);
DISPLAY 1.234043 (-2025 3875);
PAINT GREEN (-2025 3875);
DISPLAY INVISIBLE (-2025 3875);
FORCEPROP 1 LAST PATH I51
J 2
(-1700 4000);
DISPLAY 0.936170 (-1700 4000);
PAINT GREEN (-1700 4000);
DISPLAY INVISIBLE (-1700 4000);
FORCEADD TAP..6
R 2
(-1700 3900);
FORCEPROP 3 LASTPIN (-1750 3900) SIG_NAME M_M_DQ<46>
J 0
(-1740 3910);
DISPLAY 0.659574 (-1740 3910);
PAINT MONO (-1740 3910);
DISPLAY INVISIBLE (-1740 3910);
FORCEPROP 1 LASTPIN (-1750 3900) BN 46
J 2
(-1700 3910);
DISPLAY 0.617021 (-1700 3910);
PAINT PINK (-1700 3910);
FORCEPROP 2 LAST CDS_LIB mstr_standard
J 2
(-1700 3900);
DISPLAY 0.787234 (-1700 3900);
PAINT MONO (-1700 3900);
DISPLAY INVISIBLE (-1700 3900);
FORCEPROP 1 LAST BODY_TYPE PLUMBING
J 2
(-1700 3850);
DISPLAY 1.234043 (-1700 3850);
PAINT GREEN (-1700 3850);
DISPLAY INVISIBLE (-1700 3850);
FORCEPROP 1 LAST HDL_TAP TRUE
J 2
(-2025 3775);
DISPLAY 1.234043 (-2025 3775);
PAINT GREEN (-2025 3775);
DISPLAY INVISIBLE (-2025 3775);
FORCEPROP 1 LAST PATH I52
J 2
(-1700 3900);
DISPLAY 0.936170 (-1700 3900);
PAINT GREEN (-1700 3900);
DISPLAY INVISIBLE (-1700 3900);
FORCEADD TAP..6
R 2
(-1700 3800);
FORCEPROP 3 LASTPIN (-1750 3800) SIG_NAME M_M_DQ<44>
J 0
(-1740 3810);
DISPLAY 0.659574 (-1740 3810);
PAINT MONO (-1740 3810);
DISPLAY INVISIBLE (-1740 3810);
FORCEPROP 1 LASTPIN (-1750 3800) BN 44
J 2
(-1700 3810);
DISPLAY 0.617021 (-1700 3810);
PAINT PINK (-1700 3810);
FORCEPROP 2 LAST CDS_LIB mstr_standard
J 2
(-1700 3800);
DISPLAY 0.787234 (-1700 3800);
PAINT MONO (-1700 3800);
DISPLAY INVISIBLE (-1700 3800);
FORCEPROP 1 LAST BODY_TYPE PLUMBING
J 2
(-1700 3750);
DISPLAY 1.234043 (-1700 3750);
PAINT GREEN (-1700 3750);
DISPLAY INVISIBLE (-1700 3750);
FORCEPROP 1 LAST HDL_TAP TRUE
J 2
(-2025 3675);
DISPLAY 1.234043 (-2025 3675);
PAINT GREEN (-2025 3675);
DISPLAY INVISIBLE (-2025 3675);
FORCEPROP 1 LAST PATH I53
J 2
(-1700 3800);
DISPLAY 0.936170 (-1700 3800);
PAINT GREEN (-1700 3800);
DISPLAY INVISIBLE (-1700 3800);
FORCEADD TAP..6
R 2
(-1700 3850);
FORCEPROP 3 LASTPIN (-1750 3850) SIG_NAME M_M_DQ<45>
J 0
(-1740 3860);
DISPLAY 0.659574 (-1740 3860);
PAINT MONO (-1740 3860);
DISPLAY INVISIBLE (-1740 3860);
FORCEPROP 1 LASTPIN (-1750 3850) BN 45
J 2
(-1700 3860);
DISPLAY 0.617021 (-1700 3860);
PAINT PINK (-1700 3860);
FORCEPROP 2 LAST CDS_LIB mstr_standard
J 2
(-1700 3850);
DISPLAY 0.787234 (-1700 3850);
PAINT MONO (-1700 3850);
DISPLAY INVISIBLE (-1700 3850);
FORCEPROP 1 LAST BODY_TYPE PLUMBING
J 2
(-1700 3800);
DISPLAY 1.234043 (-1700 3800);
PAINT GREEN (-1700 3800);
DISPLAY INVISIBLE (-1700 3800);
FORCEPROP 1 LAST HDL_TAP TRUE
J 2
(-2025 3725);
DISPLAY 1.234043 (-2025 3725);
PAINT GREEN (-2025 3725);
DISPLAY INVISIBLE (-2025 3725);
FORCEPROP 1 LAST PATH I54
J 2
(-1700 3850);
DISPLAY 0.936170 (-1700 3850);
PAINT GREEN (-1700 3850);
DISPLAY INVISIBLE (-1700 3850);
FORCEADD TAP..6
R 2
(700 4250);
FORCEPROP 3 LASTPIN (650 4250) SIG_NAME M_M_DQS_DP<8>
J 0
(660 4260);
DISPLAY 0.659574 (660 4260);
PAINT MONO (660 4260);
DISPLAY INVISIBLE (660 4260);
FORCEPROP 1 LASTPIN (650 4250) BN 8
J 2
(700 4260);
DISPLAY 0.617021 (700 4260);
PAINT PINK (700 4260);
FORCEPROP 2 LAST CDS_LIB mstr_standard
J 0
(700 4250);
DISPLAY 0.787234 (700 4250);
PAINT MONO (700 4250);
DISPLAY INVISIBLE (700 4250);
FORCEPROP 1 LAST BODY_TYPE PLUMBING
J 2
(700 4200);
DISPLAY 1.234043 (700 4200);
PAINT GREEN (700 4200);
DISPLAY INVISIBLE (700 4200);
FORCEPROP 1 LAST HDL_TAP TRUE
J 2
(375 4125);
DISPLAY 1.234043 (375 4125);
PAINT GREEN (375 4125);
DISPLAY INVISIBLE (375 4125);
FORCEPROP 1 LAST PATH I55
J 2
(700 4250);
DISPLAY 0.936170 (700 4250);
PAINT GREEN (700 4250);
DISPLAY INVISIBLE (700 4250);
FORCEADD TAP..6
R 2
(700 4150);
FORCEPROP 3 LASTPIN (650 4150) SIG_NAME M_M_DQS_DP<7>
J 0
(660 4160);
DISPLAY 0.659574 (660 4160);
PAINT MONO (660 4160);
DISPLAY INVISIBLE (660 4160);
FORCEPROP 1 LASTPIN (650 4150) BN 7
J 2
(700 4160);
DISPLAY 0.617021 (700 4160);
PAINT PINK (700 4160);
FORCEPROP 2 LAST CDS_LIB mstr_standard
J 0
(700 4150);
DISPLAY 0.787234 (700 4150);
PAINT MONO (700 4150);
DISPLAY INVISIBLE (700 4150);
FORCEPROP 1 LAST BODY_TYPE PLUMBING
J 2
(700 4100);
DISPLAY 1.234043 (700 4100);
PAINT GREEN (700 4100);
DISPLAY INVISIBLE (700 4100);
FORCEPROP 1 LAST HDL_TAP TRUE
J 2
(375 4025);
DISPLAY 1.234043 (375 4025);
PAINT GREEN (375 4025);
DISPLAY INVISIBLE (375 4025);
FORCEPROP 1 LAST PATH I56
J 2
(700 4150);
DISPLAY 0.936170 (700 4150);
PAINT GREEN (700 4150);
DISPLAY INVISIBLE (700 4150);
FORCEADD TAP..6
R 2
(700 4050);
FORCEPROP 3 LASTPIN (650 4050) SIG_NAME M_M_DQS_DP<6>
J 0
(660 4060);
DISPLAY 0.659574 (660 4060);
PAINT MONO (660 4060);
DISPLAY INVISIBLE (660 4060);
FORCEPROP 1 LASTPIN (650 4050) BN 6
J 2
(700 4060);
DISPLAY 0.617021 (700 4060);
PAINT PINK (700 4060);
FORCEPROP 2 LAST CDS_LIB mstr_standard
J 0
(700 4050);
DISPLAY 0.787234 (700 4050);
PAINT MONO (700 4050);
DISPLAY INVISIBLE (700 4050);
FORCEPROP 1 LAST BODY_TYPE PLUMBING
J 2
(700 4000);
DISPLAY 1.234043 (700 4000);
PAINT GREEN (700 4000);
DISPLAY INVISIBLE (700 4000);
FORCEPROP 1 LAST HDL_TAP TRUE
J 2
(375 3925);
DISPLAY 1.234043 (375 3925);
PAINT GREEN (375 3925);
DISPLAY INVISIBLE (375 3925);
FORCEPROP 1 LAST PATH I57
J 2
(700 4050);
DISPLAY 0.936170 (700 4050);
PAINT GREEN (700 4050);
DISPLAY INVISIBLE (700 4050);
FORCEADD TAP..6
R 2
(700 4350);
FORCEPROP 3 LASTPIN (650 4350) SIG_NAME M_M_DQS_DP<9>
J 0
(660 4360);
DISPLAY 0.659574 (660 4360);
PAINT MONO (660 4360);
DISPLAY INVISIBLE (660 4360);
FORCEPROP 1 LASTPIN (650 4350) BN 9
J 2
(700 4360);
DISPLAY 0.617021 (700 4360);
PAINT PINK (700 4360);
FORCEPROP 2 LAST CDS_LIB mstr_standard
J 0
(700 4350);
DISPLAY 0.787234 (700 4350);
PAINT MONO (700 4350);
DISPLAY INVISIBLE (700 4350);
FORCEPROP 1 LAST BODY_TYPE PLUMBING
J 2
(700 4300);
DISPLAY 1.234043 (700 4300);
PAINT GREEN (700 4300);
DISPLAY INVISIBLE (700 4300);
FORCEPROP 1 LAST HDL_TAP TRUE
J 2
(375 4225);
DISPLAY 1.234043 (375 4225);
PAINT GREEN (375 4225);
DISPLAY INVISIBLE (375 4225);
FORCEPROP 1 LAST PATH I58
J 2
(700 4350);
DISPLAY 0.936170 (700 4350);
PAINT GREEN (700 4350);
DISPLAY INVISIBLE (700 4350);
FORCEADD TAP..6
R 2
(700 4450);
FORCEPROP 3 LASTPIN (650 4450) SIG_NAME M_M_DQS_DP<10>
J 0
(660 4460);
DISPLAY 0.659574 (660 4460);
PAINT MONO (660 4460);
DISPLAY INVISIBLE (660 4460);
FORCEPROP 1 LASTPIN (650 4450) BN 10
J 2
(700 4460);
DISPLAY 0.617021 (700 4460);
PAINT PINK (700 4460);
FORCEPROP 2 LAST CDS_LIB mstr_standard
J 0
(700 4450);
DISPLAY 0.787234 (700 4450);
PAINT MONO (700 4450);
DISPLAY INVISIBLE (700 4450);
FORCEPROP 1 LAST BODY_TYPE PLUMBING
J 2
(700 4400);
DISPLAY 1.234043 (700 4400);
PAINT GREEN (700 4400);
DISPLAY INVISIBLE (700 4400);
FORCEPROP 1 LAST HDL_TAP TRUE
J 2
(375 4325);
DISPLAY 1.234043 (375 4325);
PAINT GREEN (375 4325);
DISPLAY INVISIBLE (375 4325);
FORCEPROP 1 LAST PATH I59
J 2
(700 4450);
DISPLAY 0.936170 (700 4450);
PAINT GREEN (700 4450);
DISPLAY INVISIBLE (700 4450);
FORCEADD TAP..6
R 2
(900 4800);
FORCEPROP 3 LASTPIN (850 4800) SIG_NAME M_M_DQS_DN<14>
J 0
(860 4810);
DISPLAY 0.659574 (860 4810);
PAINT MONO (860 4810);
DISPLAY INVISIBLE (860 4810);
FORCEPROP 1 LASTPIN (850 4800) BN 14
J 2
(900 4810);
DISPLAY 0.617021 (900 4810);
PAINT PINK (900 4810);
FORCEPROP 2 LAST CDS_LIB mstr_standard
J 0
(900 4800);
DISPLAY 0.787234 (900 4800);
PAINT MONO (900 4800);
DISPLAY INVISIBLE (900 4800);
FORCEPROP 1 LAST BODY_TYPE PLUMBING
J 2
(900 4750);
DISPLAY 1.234043 (900 4750);
PAINT GREEN (900 4750);
DISPLAY INVISIBLE (900 4750);
FORCEPROP 1 LAST HDL_TAP TRUE
J 2
(575 4675);
DISPLAY 1.234043 (575 4675);
PAINT GREEN (575 4675);
DISPLAY INVISIBLE (575 4675);
FORCEPROP 1 LAST PATH I6
J 2
(900 4800);
DISPLAY 0.936170 (900 4800);
PAINT GREEN (900 4800);
DISPLAY INVISIBLE (900 4800);
FORCEADD TAP..6
R 2
(700 3750);
FORCEPROP 3 LASTPIN (650 3750) SIG_NAME M_M_DQS_DP<3>
J 0
(660 3760);
DISPLAY 0.659574 (660 3760);
PAINT MONO (660 3760);
DISPLAY INVISIBLE (660 3760);
FORCEPROP 1 LASTPIN (650 3750) BN 3
J 2
(700 3760);
DISPLAY 0.617021 (700 3760);
PAINT PINK (700 3760);
FORCEPROP 2 LAST CDS_LIB mstr_standard
J 0
(700 3750);
DISPLAY 0.787234 (700 3750);
PAINT MONO (700 3750);
DISPLAY INVISIBLE (700 3750);
FORCEPROP 1 LAST BODY_TYPE PLUMBING
J 2
(700 3700);
DISPLAY 1.234043 (700 3700);
PAINT GREEN (700 3700);
DISPLAY INVISIBLE (700 3700);
FORCEPROP 1 LAST HDL_TAP TRUE
J 2
(375 3625);
DISPLAY 1.234043 (375 3625);
PAINT GREEN (375 3625);
DISPLAY INVISIBLE (375 3625);
FORCEPROP 1 LAST PATH I60
J 2
(700 3750);
DISPLAY 0.936170 (700 3750);
PAINT GREEN (700 3750);
DISPLAY INVISIBLE (700 3750);
FORCEADD TAP..6
R 2
(700 3550);
FORCEPROP 3 LASTPIN (650 3550) SIG_NAME M_M_DQS_DP<1>
J 0
(660 3560);
DISPLAY 0.659574 (660 3560);
PAINT MONO (660 3560);
DISPLAY INVISIBLE (660 3560);
FORCEPROP 1 LASTPIN (650 3550) BN 1
J 2
(700 3560);
DISPLAY 0.617021 (700 3560);
PAINT PINK (700 3560);
FORCEPROP 2 LAST CDS_LIB mstr_standard
J 0
(700 3550);
DISPLAY 0.787234 (700 3550);
PAINT MONO (700 3550);
DISPLAY INVISIBLE (700 3550);
FORCEPROP 1 LAST BODY_TYPE PLUMBING
J 2
(700 3500);
DISPLAY 1.234043 (700 3500);
PAINT GREEN (700 3500);
DISPLAY INVISIBLE (700 3500);
FORCEPROP 1 LAST HDL_TAP TRUE
J 2
(375 3425);
DISPLAY 1.234043 (375 3425);
PAINT GREEN (375 3425);
DISPLAY INVISIBLE (375 3425);
FORCEPROP 1 LAST PATH I61
J 2
(700 3550);
DISPLAY 0.936170 (700 3550);
PAINT GREEN (700 3550);
DISPLAY INVISIBLE (700 3550);
FORCEADD TAP..6
R 2
(700 3650);
FORCEPROP 3 LASTPIN (650 3650) SIG_NAME M_M_DQS_DP<2>
J 0
(660 3660);
DISPLAY 0.659574 (660 3660);
PAINT MONO (660 3660);
DISPLAY INVISIBLE (660 3660);
FORCEPROP 1 LASTPIN (650 3650) BN 2
J 2
(700 3660);
DISPLAY 0.617021 (700 3660);
PAINT PINK (700 3660);
FORCEPROP 2 LAST CDS_LIB mstr_standard
J 0
(700 3650);
DISPLAY 0.787234 (700 3650);
PAINT MONO (700 3650);
DISPLAY INVISIBLE (700 3650);
FORCEPROP 1 LAST BODY_TYPE PLUMBING
J 2
(700 3600);
DISPLAY 1.234043 (700 3600);
PAINT GREEN (700 3600);
DISPLAY INVISIBLE (700 3600);
FORCEPROP 1 LAST HDL_TAP TRUE
J 2
(375 3525);
DISPLAY 1.234043 (375 3525);
PAINT GREEN (375 3525);
DISPLAY INVISIBLE (375 3525);
FORCEPROP 1 LAST PATH I62
J 2
(700 3650);
DISPLAY 0.936170 (700 3650);
PAINT GREEN (700 3650);
DISPLAY INVISIBLE (700 3650);
FORCEADD TAP..6
R 2
(700 3950);
FORCEPROP 3 LASTPIN (650 3950) SIG_NAME M_M_DQS_DP<5>
J 0
(660 3960);
DISPLAY 0.659574 (660 3960);
PAINT MONO (660 3960);
DISPLAY INVISIBLE (660 3960);
FORCEPROP 1 LASTPIN (650 3950) BN 5
J 2
(700 3960);
DISPLAY 0.617021 (700 3960);
PAINT PINK (700 3960);
FORCEPROP 2 LAST CDS_LIB mstr_standard
J 0
(700 3950);
DISPLAY 0.787234 (700 3950);
PAINT MONO (700 3950);
DISPLAY INVISIBLE (700 3950);
FORCEPROP 1 LAST BODY_TYPE PLUMBING
J 2
(700 3900);
DISPLAY 1.234043 (700 3900);
PAINT GREEN (700 3900);
DISPLAY INVISIBLE (700 3900);
FORCEPROP 1 LAST HDL_TAP TRUE
J 2
(375 3825);
DISPLAY 1.234043 (375 3825);
PAINT GREEN (375 3825);
DISPLAY INVISIBLE (375 3825);
FORCEPROP 1 LAST PATH I63
J 2
(700 3950);
DISPLAY 0.936170 (700 3950);
PAINT GREEN (700 3950);
DISPLAY INVISIBLE (700 3950);
FORCEADD TAP..6
R 2
(700 3850);
FORCEPROP 3 LASTPIN (650 3850) SIG_NAME M_M_DQS_DP<4>
J 0
(660 3860);
DISPLAY 0.659574 (660 3860);
PAINT MONO (660 3860);
DISPLAY INVISIBLE (660 3860);
FORCEPROP 1 LASTPIN (650 3850) BN 4
J 2
(700 3860);
DISPLAY 0.617021 (700 3860);
PAINT PINK (700 3860);
FORCEPROP 2 LAST CDS_LIB mstr_standard
J 0
(700 3850);
DISPLAY 0.787234 (700 3850);
PAINT MONO (700 3850);
DISPLAY INVISIBLE (700 3850);
FORCEPROP 1 LAST BODY_TYPE PLUMBING
J 2
(700 3800);
DISPLAY 1.234043 (700 3800);
PAINT GREEN (700 3800);
DISPLAY INVISIBLE (700 3800);
FORCEPROP 1 LAST HDL_TAP TRUE
J 2
(375 3725);
DISPLAY 1.234043 (375 3725);
PAINT GREEN (375 3725);
DISPLAY INVISIBLE (375 3725);
FORCEPROP 1 LAST PATH I64
J 2
(700 3850);
DISPLAY 0.936170 (700 3850);
PAINT GREEN (700 3850);
DISPLAY INVISIBLE (700 3850);
FORCEADD TAP..6
R 2
(700 3450);
FORCEPROP 3 LASTPIN (650 3450) SIG_NAME M_M_DQS_DP<0>
J 0
(660 3460);
DISPLAY 0.659574 (660 3460);
PAINT MONO (660 3460);
DISPLAY INVISIBLE (660 3460);
FORCEPROP 1 LASTPIN (650 3450) BN 0
J 2
(700 3460);
DISPLAY 0.617021 (700 3460);
PAINT PINK (700 3460);
FORCEPROP 2 LAST CDS_LIB mstr_standard
J 0
(700 3450);
DISPLAY 0.787234 (700 3450);
PAINT MONO (700 3450);
DISPLAY INVISIBLE (700 3450);
FORCEPROP 1 LAST BODY_TYPE PLUMBING
J 2
(700 3400);
DISPLAY 1.234043 (700 3400);
PAINT GREEN (700 3400);
DISPLAY INVISIBLE (700 3400);
FORCEPROP 1 LAST HDL_TAP TRUE
J 2
(375 3325);
DISPLAY 1.234043 (375 3325);
PAINT GREEN (375 3325);
DISPLAY INVISIBLE (375 3325);
FORCEPROP 1 LAST PATH I65
J 2
(700 3450);
DISPLAY 0.936170 (700 3450);
PAINT GREEN (700 3450);
DISPLAY INVISIBLE (700 3450);
FORCEADD TAP..6
R 2
(-1700 3750);
FORCEPROP 3 LASTPIN (-1750 3750) SIG_NAME M_M_DQ<43>
J 0
(-1740 3760);
DISPLAY 0.659574 (-1740 3760);
PAINT MONO (-1740 3760);
DISPLAY INVISIBLE (-1740 3760);
FORCEPROP 1 LASTPIN (-1750 3750) BN 43
J 2
(-1700 3760);
DISPLAY 0.617021 (-1700 3760);
PAINT PINK (-1700 3760);
FORCEPROP 2 LAST CDS_LIB mstr_standard
J 2
(-1700 3750);
DISPLAY 0.787234 (-1700 3750);
PAINT MONO (-1700 3750);
DISPLAY INVISIBLE (-1700 3750);
FORCEPROP 1 LAST BODY_TYPE PLUMBING
J 2
(-1700 3700);
DISPLAY 1.234043 (-1700 3700);
PAINT GREEN (-1700 3700);
DISPLAY INVISIBLE (-1700 3700);
FORCEPROP 1 LAST HDL_TAP TRUE
J 2
(-2025 3625);
DISPLAY 1.234043 (-2025 3625);
PAINT GREEN (-2025 3625);
DISPLAY INVISIBLE (-2025 3625);
FORCEPROP 1 LAST PATH I66
J 2
(-1700 3750);
DISPLAY 0.936170 (-1700 3750);
PAINT GREEN (-1700 3750);
DISPLAY INVISIBLE (-1700 3750);
FORCEADD TAP..6
R 2
(-1700 3700);
FORCEPROP 3 LASTPIN (-1750 3700) SIG_NAME M_M_DQ<42>
J 0
(-1740 3710);
DISPLAY 0.659574 (-1740 3710);
PAINT MONO (-1740 3710);
DISPLAY INVISIBLE (-1740 3710);
FORCEPROP 1 LASTPIN (-1750 3700) BN 42
J 2
(-1700 3710);
DISPLAY 0.617021 (-1700 3710);
PAINT PINK (-1700 3710);
FORCEPROP 2 LAST CDS_LIB mstr_standard
J 2
(-1700 3700);
DISPLAY 0.787234 (-1700 3700);
PAINT MONO (-1700 3700);
DISPLAY INVISIBLE (-1700 3700);
FORCEPROP 1 LAST BODY_TYPE PLUMBING
J 2
(-1700 3650);
DISPLAY 1.234043 (-1700 3650);
PAINT GREEN (-1700 3650);
DISPLAY INVISIBLE (-1700 3650);
FORCEPROP 1 LAST HDL_TAP TRUE
J 2
(-2025 3575);
DISPLAY 1.234043 (-2025 3575);
PAINT GREEN (-2025 3575);
DISPLAY INVISIBLE (-2025 3575);
FORCEPROP 1 LAST PATH I67
J 2
(-1700 3700);
DISPLAY 0.936170 (-1700 3700);
PAINT GREEN (-1700 3700);
DISPLAY INVISIBLE (-1700 3700);
FORCEADD TAP..6
R 2
(-1700 3600);
FORCEPROP 3 LASTPIN (-1750 3600) SIG_NAME M_M_DQ<40>
J 0
(-1740 3610);
DISPLAY 0.659574 (-1740 3610);
PAINT MONO (-1740 3610);
DISPLAY INVISIBLE (-1740 3610);
FORCEPROP 1 LASTPIN (-1750 3600) BN 40
J 2
(-1700 3610);
DISPLAY 0.617021 (-1700 3610);
PAINT PINK (-1700 3610);
FORCEPROP 2 LAST CDS_LIB mstr_standard
J 2
(-1700 3600);
DISPLAY 0.787234 (-1700 3600);
PAINT MONO (-1700 3600);
DISPLAY INVISIBLE (-1700 3600);
FORCEPROP 1 LAST BODY_TYPE PLUMBING
J 2
(-1700 3550);
DISPLAY 1.234043 (-1700 3550);
PAINT GREEN (-1700 3550);
DISPLAY INVISIBLE (-1700 3550);
FORCEPROP 1 LAST HDL_TAP TRUE
J 2
(-2025 3475);
DISPLAY 1.234043 (-2025 3475);
PAINT GREEN (-2025 3475);
DISPLAY INVISIBLE (-2025 3475);
FORCEPROP 1 LAST PATH I68
J 2
(-1700 3600);
DISPLAY 0.936170 (-1700 3600);
PAINT GREEN (-1700 3600);
DISPLAY INVISIBLE (-1700 3600);
FORCEADD TAP..6
R 2
(-1700 3650);
FORCEPROP 3 LASTPIN (-1750 3650) SIG_NAME M_M_DQ<41>
J 0
(-1740 3660);
DISPLAY 0.659574 (-1740 3660);
PAINT MONO (-1740 3660);
DISPLAY INVISIBLE (-1740 3660);
FORCEPROP 1 LASTPIN (-1750 3650) BN 41
J 2
(-1700 3660);
DISPLAY 0.617021 (-1700 3660);
PAINT PINK (-1700 3660);
FORCEPROP 2 LAST CDS_LIB mstr_standard
J 2
(-1700 3650);
DISPLAY 0.787234 (-1700 3650);
PAINT MONO (-1700 3650);
DISPLAY INVISIBLE (-1700 3650);
FORCEPROP 1 LAST BODY_TYPE PLUMBING
J 2
(-1700 3600);
DISPLAY 1.234043 (-1700 3600);
PAINT GREEN (-1700 3600);
DISPLAY INVISIBLE (-1700 3600);
FORCEPROP 1 LAST HDL_TAP TRUE
J 2
(-2025 3525);
DISPLAY 1.234043 (-2025 3525);
PAINT GREEN (-2025 3525);
DISPLAY INVISIBLE (-2025 3525);
FORCEPROP 1 LAST PATH I69
J 2
(-1700 3650);
DISPLAY 0.936170 (-1700 3650);
PAINT GREEN (-1700 3650);
DISPLAY INVISIBLE (-1700 3650);
FORCEADD TAP..6
R 2
(900 4700);
FORCEPROP 3 LASTPIN (850 4700) SIG_NAME M_M_DQS_DN<13>
J 0
(860 4710);
DISPLAY 0.659574 (860 4710);
PAINT MONO (860 4710);
DISPLAY INVISIBLE (860 4710);
FORCEPROP 1 LASTPIN (850 4700) BN 13
J 2
(900 4710);
DISPLAY 0.617021 (900 4710);
PAINT PINK (900 4710);
FORCEPROP 2 LAST CDS_LIB mstr_standard
J 0
(900 4700);
DISPLAY 0.787234 (900 4700);
PAINT MONO (900 4700);
DISPLAY INVISIBLE (900 4700);
FORCEPROP 1 LAST BODY_TYPE PLUMBING
J 2
(900 4650);
DISPLAY 1.234043 (900 4650);
PAINT GREEN (900 4650);
DISPLAY INVISIBLE (900 4650);
FORCEPROP 1 LAST HDL_TAP TRUE
J 2
(575 4575);
DISPLAY 1.234043 (575 4575);
PAINT GREEN (575 4575);
DISPLAY INVISIBLE (575 4575);
FORCEPROP 1 LAST PATH I7
J 2
(900 4700);
DISPLAY 0.936170 (900 4700);
PAINT GREEN (900 4700);
DISPLAY INVISIBLE (900 4700);
FORCEADD TAP..6
R 2
(-1700 3550);
FORCEPROP 3 LASTPIN (-1750 3550) SIG_NAME M_M_DQ<39>
J 0
(-1740 3560);
DISPLAY 0.659574 (-1740 3560);
PAINT MONO (-1740 3560);
DISPLAY INVISIBLE (-1740 3560);
FORCEPROP 1 LASTPIN (-1750 3550) BN 39
J 2
(-1700 3560);
DISPLAY 0.617021 (-1700 3560);
PAINT PINK (-1700 3560);
FORCEPROP 2 LAST CDS_LIB mstr_standard
J 2
(-1700 3550);
DISPLAY 0.787234 (-1700 3550);
PAINT MONO (-1700 3550);
DISPLAY INVISIBLE (-1700 3550);
FORCEPROP 1 LAST BODY_TYPE PLUMBING
J 2
(-1700 3500);
DISPLAY 1.234043 (-1700 3500);
PAINT GREEN (-1700 3500);
DISPLAY INVISIBLE (-1700 3500);
FORCEPROP 1 LAST HDL_TAP TRUE
J 2
(-2025 3425);
DISPLAY 1.234043 (-2025 3425);
PAINT GREEN (-2025 3425);
DISPLAY INVISIBLE (-2025 3425);
FORCEPROP 1 LAST PATH I70
J 2
(-1700 3550);
DISPLAY 0.936170 (-1700 3550);
PAINT GREEN (-1700 3550);
DISPLAY INVISIBLE (-1700 3550);
FORCEADD TAP..6
R 2
(-1700 3500);
FORCEPROP 3 LASTPIN (-1750 3500) SIG_NAME M_M_DQ<38>
J 0
(-1740 3510);
DISPLAY 0.659574 (-1740 3510);
PAINT MONO (-1740 3510);
DISPLAY INVISIBLE (-1740 3510);
FORCEPROP 1 LASTPIN (-1750 3500) BN 38
J 2
(-1700 3510);
DISPLAY 0.617021 (-1700 3510);
PAINT PINK (-1700 3510);
FORCEPROP 2 LAST CDS_LIB mstr_standard
J 2
(-1700 3500);
DISPLAY 0.787234 (-1700 3500);
PAINT MONO (-1700 3500);
DISPLAY INVISIBLE (-1700 3500);
FORCEPROP 1 LAST BODY_TYPE PLUMBING
J 2
(-1700 3450);
DISPLAY 1.234043 (-1700 3450);
PAINT GREEN (-1700 3450);
DISPLAY INVISIBLE (-1700 3450);
FORCEPROP 1 LAST HDL_TAP TRUE
J 2
(-2025 3375);
DISPLAY 1.234043 (-2025 3375);
PAINT GREEN (-2025 3375);
DISPLAY INVISIBLE (-2025 3375);
FORCEPROP 1 LAST PATH I71
J 2
(-1700 3500);
DISPLAY 0.936170 (-1700 3500);
PAINT GREEN (-1700 3500);
DISPLAY INVISIBLE (-1700 3500);
FORCEADD TAP..6
R 2
(-1700 3450);
FORCEPROP 3 LASTPIN (-1750 3450) SIG_NAME M_M_DQ<37>
J 0
(-1740 3460);
DISPLAY 0.659574 (-1740 3460);
PAINT MONO (-1740 3460);
DISPLAY INVISIBLE (-1740 3460);
FORCEPROP 1 LASTPIN (-1750 3450) BN 37
J 2
(-1700 3460);
DISPLAY 0.617021 (-1700 3460);
PAINT PINK (-1700 3460);
FORCEPROP 2 LAST CDS_LIB mstr_standard
J 2
(-1700 3450);
DISPLAY 0.787234 (-1700 3450);
PAINT MONO (-1700 3450);
DISPLAY INVISIBLE (-1700 3450);
FORCEPROP 1 LAST BODY_TYPE PLUMBING
J 2
(-1700 3400);
DISPLAY 1.234043 (-1700 3400);
PAINT GREEN (-1700 3400);
DISPLAY INVISIBLE (-1700 3400);
FORCEPROP 1 LAST HDL_TAP TRUE
J 2
(-2025 3325);
DISPLAY 1.234043 (-2025 3325);
PAINT GREEN (-2025 3325);
DISPLAY INVISIBLE (-2025 3325);
FORCEPROP 1 LAST PATH I72
J 2
(-1700 3450);
DISPLAY 0.936170 (-1700 3450);
PAINT GREEN (-1700 3450);
DISPLAY INVISIBLE (-1700 3450);
FORCEADD TAP..6
R 2
(-1700 3400);
FORCEPROP 3 LASTPIN (-1750 3400) SIG_NAME M_M_DQ<36>
J 0
(-1740 3410);
DISPLAY 0.659574 (-1740 3410);
PAINT MONO (-1740 3410);
DISPLAY INVISIBLE (-1740 3410);
FORCEPROP 1 LASTPIN (-1750 3400) BN 36
J 2
(-1700 3410);
DISPLAY 0.617021 (-1700 3410);
PAINT PINK (-1700 3410);
FORCEPROP 2 LAST CDS_LIB mstr_standard
J 2
(-1700 3400);
DISPLAY 0.787234 (-1700 3400);
PAINT MONO (-1700 3400);
DISPLAY INVISIBLE (-1700 3400);
FORCEPROP 1 LAST BODY_TYPE PLUMBING
J 2
(-1700 3350);
DISPLAY 1.234043 (-1700 3350);
PAINT GREEN (-1700 3350);
DISPLAY INVISIBLE (-1700 3350);
FORCEPROP 1 LAST HDL_TAP TRUE
J 2
(-2025 3275);
DISPLAY 1.234043 (-2025 3275);
PAINT GREEN (-2025 3275);
DISPLAY INVISIBLE (-2025 3275);
FORCEPROP 1 LAST PATH I73
J 2
(-1700 3400);
DISPLAY 0.936170 (-1700 3400);
PAINT GREEN (-1700 3400);
DISPLAY INVISIBLE (-1700 3400);
FORCEADD TAP..6
R 2
(-1700 3350);
FORCEPROP 3 LASTPIN (-1750 3350) SIG_NAME M_M_DQ<35>
J 0
(-1740 3360);
DISPLAY 0.659574 (-1740 3360);
PAINT MONO (-1740 3360);
DISPLAY INVISIBLE (-1740 3360);
FORCEPROP 1 LASTPIN (-1750 3350) BN 35
J 2
(-1700 3360);
DISPLAY 0.617021 (-1700 3360);
PAINT PINK (-1700 3360);
FORCEPROP 2 LAST CDS_LIB mstr_standard
J 2
(-1700 3350);
DISPLAY 0.787234 (-1700 3350);
PAINT MONO (-1700 3350);
DISPLAY INVISIBLE (-1700 3350);
FORCEPROP 1 LAST BODY_TYPE PLUMBING
J 2
(-1700 3300);
DISPLAY 1.234043 (-1700 3300);
PAINT GREEN (-1700 3300);
DISPLAY INVISIBLE (-1700 3300);
FORCEPROP 1 LAST HDL_TAP TRUE
J 2
(-2025 3225);
DISPLAY 1.234043 (-2025 3225);
PAINT GREEN (-2025 3225);
DISPLAY INVISIBLE (-2025 3225);
FORCEPROP 1 LAST PATH I74
J 2
(-1700 3350);
DISPLAY 0.936170 (-1700 3350);
PAINT GREEN (-1700 3350);
DISPLAY INVISIBLE (-1700 3350);
FORCEADD TAP..6
R 2
(-1700 3300);
FORCEPROP 3 LASTPIN (-1750 3300) SIG_NAME M_M_DQ<34>
J 0
(-1740 3310);
DISPLAY 0.659574 (-1740 3310);
PAINT MONO (-1740 3310);
DISPLAY INVISIBLE (-1740 3310);
FORCEPROP 1 LASTPIN (-1750 3300) BN 34
J 2
(-1700 3310);
DISPLAY 0.617021 (-1700 3310);
PAINT PINK (-1700 3310);
FORCEPROP 2 LAST CDS_LIB mstr_standard
J 2
(-1700 3300);
DISPLAY 0.787234 (-1700 3300);
PAINT MONO (-1700 3300);
DISPLAY INVISIBLE (-1700 3300);
FORCEPROP 1 LAST BODY_TYPE PLUMBING
J 2
(-1700 3250);
DISPLAY 1.234043 (-1700 3250);
PAINT GREEN (-1700 3250);
DISPLAY INVISIBLE (-1700 3250);
FORCEPROP 1 LAST HDL_TAP TRUE
J 2
(-2025 3175);
DISPLAY 1.234043 (-2025 3175);
PAINT GREEN (-2025 3175);
DISPLAY INVISIBLE (-2025 3175);
FORCEPROP 1 LAST PATH I75
J 2
(-1700 3300);
DISPLAY 0.936170 (-1700 3300);
PAINT GREEN (-1700 3300);
DISPLAY INVISIBLE (-1700 3300);
FORCEADD TAP..6
R 2
(-1700 3250);
FORCEPROP 3 LASTPIN (-1750 3250) SIG_NAME M_M_DQ<33>
J 0
(-1740 3260);
DISPLAY 0.659574 (-1740 3260);
PAINT MONO (-1740 3260);
DISPLAY INVISIBLE (-1740 3260);
FORCEPROP 1 LASTPIN (-1750 3250) BN 33
J 2
(-1700 3260);
DISPLAY 0.617021 (-1700 3260);
PAINT PINK (-1700 3260);
FORCEPROP 2 LAST CDS_LIB mstr_standard
J 2
(-1700 3250);
DISPLAY 0.787234 (-1700 3250);
PAINT MONO (-1700 3250);
DISPLAY INVISIBLE (-1700 3250);
FORCEPROP 1 LAST BODY_TYPE PLUMBING
J 2
(-1700 3200);
DISPLAY 1.234043 (-1700 3200);
PAINT GREEN (-1700 3200);
DISPLAY INVISIBLE (-1700 3200);
FORCEPROP 1 LAST HDL_TAP TRUE
J 2
(-2025 3125);
DISPLAY 1.234043 (-2025 3125);
PAINT GREEN (-2025 3125);
DISPLAY INVISIBLE (-2025 3125);
FORCEPROP 1 LAST PATH I76
J 2
(-1700 3250);
DISPLAY 0.936170 (-1700 3250);
PAINT GREEN (-1700 3250);
DISPLAY INVISIBLE (-1700 3250);
FORCEADD TAP..6
R 2
(-1700 3200);
FORCEPROP 3 LASTPIN (-1750 3200) SIG_NAME M_M_DQ<32>
J 0
(-1740 3210);
DISPLAY 0.659574 (-1740 3210);
PAINT MONO (-1740 3210);
DISPLAY INVISIBLE (-1740 3210);
FORCEPROP 1 LASTPIN (-1750 3200) BN 32
J 2
(-1700 3210);
DISPLAY 0.617021 (-1700 3210);
PAINT PINK (-1700 3210);
FORCEPROP 2 LAST CDS_LIB mstr_standard
J 2
(-1700 3200);
DISPLAY 0.787234 (-1700 3200);
PAINT MONO (-1700 3200);
DISPLAY INVISIBLE (-1700 3200);
FORCEPROP 1 LAST BODY_TYPE PLUMBING
J 2
(-1700 3150);
DISPLAY 1.234043 (-1700 3150);
PAINT GREEN (-1700 3150);
DISPLAY INVISIBLE (-1700 3150);
FORCEPROP 1 LAST HDL_TAP TRUE
J 2
(-2025 3075);
DISPLAY 1.234043 (-2025 3075);
PAINT GREEN (-2025 3075);
DISPLAY INVISIBLE (-2025 3075);
FORCEPROP 1 LAST PATH I77
J 2
(-1700 3200);
DISPLAY 0.936170 (-1700 3200);
PAINT GREEN (-1700 3200);
DISPLAY INVISIBLE (-1700 3200);
FORCEADD TAP..6
R 2
(-1700 3050);
FORCEPROP 3 LASTPIN (-1750 3050) SIG_NAME M_M_DQ<29>
J 0
(-1740 3060);
DISPLAY 0.659574 (-1740 3060);
PAINT MONO (-1740 3060);
DISPLAY INVISIBLE (-1740 3060);
FORCEPROP 1 LASTPIN (-1750 3050) BN 29
J 2
(-1700 3060);
DISPLAY 0.617021 (-1700 3060);
PAINT PINK (-1700 3060);
FORCEPROP 2 LAST CDS_LIB mstr_standard
J 2
(-1700 3050);
DISPLAY 0.787234 (-1700 3050);
PAINT MONO (-1700 3050);
DISPLAY INVISIBLE (-1700 3050);
FORCEPROP 1 LAST BODY_TYPE PLUMBING
J 2
(-1700 3000);
DISPLAY 1.234043 (-1700 3000);
PAINT GREEN (-1700 3000);
DISPLAY INVISIBLE (-1700 3000);
FORCEPROP 1 LAST HDL_TAP TRUE
J 2
(-2025 2925);
DISPLAY 1.234043 (-2025 2925);
PAINT GREEN (-2025 2925);
DISPLAY INVISIBLE (-2025 2925);
FORCEPROP 1 LAST PATH I78
J 2
(-1700 3050);
DISPLAY 0.936170 (-1700 3050);
PAINT GREEN (-1700 3050);
DISPLAY INVISIBLE (-1700 3050);
FORCEADD TAP..6
R 2
(-1700 3100);
FORCEPROP 3 LASTPIN (-1750 3100) SIG_NAME M_M_DQ<30>
J 0
(-1740 3110);
DISPLAY 0.659574 (-1740 3110);
PAINT MONO (-1740 3110);
DISPLAY INVISIBLE (-1740 3110);
FORCEPROP 1 LASTPIN (-1750 3100) BN 30
J 2
(-1700 3110);
DISPLAY 0.617021 (-1700 3110);
PAINT PINK (-1700 3110);
FORCEPROP 2 LAST CDS_LIB mstr_standard
J 2
(-1700 3100);
DISPLAY 0.787234 (-1700 3100);
PAINT MONO (-1700 3100);
DISPLAY INVISIBLE (-1700 3100);
FORCEPROP 1 LAST BODY_TYPE PLUMBING
J 2
(-1700 3050);
DISPLAY 1.234043 (-1700 3050);
PAINT GREEN (-1700 3050);
DISPLAY INVISIBLE (-1700 3050);
FORCEPROP 1 LAST HDL_TAP TRUE
J 2
(-2025 2975);
DISPLAY 1.234043 (-2025 2975);
PAINT GREEN (-2025 2975);
DISPLAY INVISIBLE (-2025 2975);
FORCEPROP 1 LAST PATH I79
J 2
(-1700 3100);
DISPLAY 0.936170 (-1700 3100);
PAINT GREEN (-1700 3100);
DISPLAY INVISIBLE (-1700 3100);
FORCEADD TAP..6
R 2
(900 4600);
FORCEPROP 3 LASTPIN (850 4600) SIG_NAME M_M_DQS_DN<12>
J 0
(860 4610);
DISPLAY 0.659574 (860 4610);
PAINT MONO (860 4610);
DISPLAY INVISIBLE (860 4610);
FORCEPROP 1 LASTPIN (850 4600) BN 12
J 2
(900 4610);
DISPLAY 0.617021 (900 4610);
PAINT PINK (900 4610);
FORCEPROP 2 LAST CDS_LIB mstr_standard
J 0
(900 4600);
DISPLAY 0.787234 (900 4600);
PAINT MONO (900 4600);
DISPLAY INVISIBLE (900 4600);
FORCEPROP 1 LAST BODY_TYPE PLUMBING
J 2
(900 4550);
DISPLAY 1.234043 (900 4550);
PAINT GREEN (900 4550);
DISPLAY INVISIBLE (900 4550);
FORCEPROP 1 LAST HDL_TAP TRUE
J 2
(575 4475);
DISPLAY 1.234043 (575 4475);
PAINT GREEN (575 4475);
DISPLAY INVISIBLE (575 4475);
FORCEPROP 1 LAST PATH I8
J 2
(900 4600);
DISPLAY 0.936170 (900 4600);
PAINT GREEN (900 4600);
DISPLAY INVISIBLE (900 4600);
FORCEADD TAP..6
R 2
(-1700 3150);
FORCEPROP 3 LASTPIN (-1750 3150) SIG_NAME M_M_DQ<31>
J 0
(-1740 3160);
DISPLAY 0.659574 (-1740 3160);
PAINT MONO (-1740 3160);
DISPLAY INVISIBLE (-1740 3160);
FORCEPROP 1 LASTPIN (-1750 3150) BN 31
J 2
(-1700 3160);
DISPLAY 0.617021 (-1700 3160);
PAINT PINK (-1700 3160);
FORCEPROP 2 LAST CDS_LIB mstr_standard
J 2
(-1700 3150);
DISPLAY 0.787234 (-1700 3150);
PAINT MONO (-1700 3150);
DISPLAY INVISIBLE (-1700 3150);
FORCEPROP 1 LAST BODY_TYPE PLUMBING
J 2
(-1700 3100);
DISPLAY 1.234043 (-1700 3100);
PAINT GREEN (-1700 3100);
DISPLAY INVISIBLE (-1700 3100);
FORCEPROP 1 LAST HDL_TAP TRUE
J 2
(-2025 3025);
DISPLAY 1.234043 (-2025 3025);
PAINT GREEN (-2025 3025);
DISPLAY INVISIBLE (-2025 3025);
FORCEPROP 1 LAST PATH I80
J 2
(-1700 3150);
DISPLAY 0.936170 (-1700 3150);
PAINT GREEN (-1700 3150);
DISPLAY INVISIBLE (-1700 3150);
FORCEADD TAP..6
R 2
(-1700 2750);
FORCEPROP 3 LASTPIN (-1750 2750) SIG_NAME M_M_DQ<23>
J 0
(-1740 2760);
DISPLAY 0.659574 (-1740 2760);
PAINT MONO (-1740 2760);
DISPLAY INVISIBLE (-1740 2760);
FORCEPROP 1 LASTPIN (-1750 2750) BN 23
J 2
(-1700 2760);
DISPLAY 0.617021 (-1700 2760);
PAINT PINK (-1700 2760);
FORCEPROP 2 LAST CDS_LIB mstr_standard
J 2
(-1700 2750);
DISPLAY 0.787234 (-1700 2750);
PAINT MONO (-1700 2750);
DISPLAY INVISIBLE (-1700 2750);
FORCEPROP 1 LAST BODY_TYPE PLUMBING
J 2
(-1700 2700);
DISPLAY 1.234043 (-1700 2700);
PAINT GREEN (-1700 2700);
DISPLAY INVISIBLE (-1700 2700);
FORCEPROP 1 LAST HDL_TAP TRUE
J 2
(-2025 2625);
DISPLAY 1.234043 (-2025 2625);
PAINT GREEN (-2025 2625);
DISPLAY INVISIBLE (-2025 2625);
FORCEPROP 1 LAST PATH I81
J 2
(-1700 2750);
DISPLAY 0.936170 (-1700 2750);
PAINT GREEN (-1700 2750);
DISPLAY INVISIBLE (-1700 2750);
FORCEADD TAP..6
R 2
(-1700 2950);
FORCEPROP 3 LASTPIN (-1750 2950) SIG_NAME M_M_DQ<27>
J 0
(-1740 2960);
DISPLAY 0.659574 (-1740 2960);
PAINT MONO (-1740 2960);
DISPLAY INVISIBLE (-1740 2960);
FORCEPROP 1 LASTPIN (-1750 2950) BN 27
J 2
(-1700 2960);
DISPLAY 0.617021 (-1700 2960);
PAINT PINK (-1700 2960);
FORCEPROP 2 LAST CDS_LIB mstr_standard
J 2
(-1700 2950);
DISPLAY 0.787234 (-1700 2950);
PAINT MONO (-1700 2950);
DISPLAY INVISIBLE (-1700 2950);
FORCEPROP 1 LAST BODY_TYPE PLUMBING
J 2
(-1700 2900);
DISPLAY 1.234043 (-1700 2900);
PAINT GREEN (-1700 2900);
DISPLAY INVISIBLE (-1700 2900);
FORCEPROP 1 LAST HDL_TAP TRUE
J 2
(-2025 2825);
DISPLAY 1.234043 (-2025 2825);
PAINT GREEN (-2025 2825);
DISPLAY INVISIBLE (-2025 2825);
FORCEPROP 1 LAST PATH I82
J 2
(-1700 2950);
DISPLAY 0.936170 (-1700 2950);
PAINT GREEN (-1700 2950);
DISPLAY INVISIBLE (-1700 2950);
FORCEADD TAP..6
R 2
(-1700 3000);
FORCEPROP 3 LASTPIN (-1750 3000) SIG_NAME M_M_DQ<28>
J 0
(-1740 3010);
DISPLAY 0.659574 (-1740 3010);
PAINT MONO (-1740 3010);
DISPLAY INVISIBLE (-1740 3010);
FORCEPROP 1 LASTPIN (-1750 3000) BN 28
J 2
(-1700 3010);
DISPLAY 0.617021 (-1700 3010);
PAINT PINK (-1700 3010);
FORCEPROP 2 LAST CDS_LIB mstr_standard
J 2
(-1700 3000);
DISPLAY 0.787234 (-1700 3000);
PAINT MONO (-1700 3000);
DISPLAY INVISIBLE (-1700 3000);
FORCEPROP 1 LAST BODY_TYPE PLUMBING
J 2
(-1700 2950);
DISPLAY 1.234043 (-1700 2950);
PAINT GREEN (-1700 2950);
DISPLAY INVISIBLE (-1700 2950);
FORCEPROP 1 LAST HDL_TAP TRUE
J 2
(-2025 2875);
DISPLAY 1.234043 (-2025 2875);
PAINT GREEN (-2025 2875);
DISPLAY INVISIBLE (-2025 2875);
FORCEPROP 1 LAST PATH I83
J 2
(-1700 3000);
DISPLAY 0.936170 (-1700 3000);
PAINT GREEN (-1700 3000);
DISPLAY INVISIBLE (-1700 3000);
FORCEADD TAP..6
R 2
(-1700 2900);
FORCEPROP 3 LASTPIN (-1750 2900) SIG_NAME M_M_DQ<26>
J 0
(-1740 2910);
DISPLAY 0.659574 (-1740 2910);
PAINT MONO (-1740 2910);
DISPLAY INVISIBLE (-1740 2910);
FORCEPROP 1 LASTPIN (-1750 2900) BN 26
J 2
(-1700 2910);
DISPLAY 0.617021 (-1700 2910);
PAINT PINK (-1700 2910);
FORCEPROP 2 LAST CDS_LIB mstr_standard
J 2
(-1700 2900);
DISPLAY 0.787234 (-1700 2900);
PAINT MONO (-1700 2900);
DISPLAY INVISIBLE (-1700 2900);
FORCEPROP 1 LAST BODY_TYPE PLUMBING
J 2
(-1700 2850);
DISPLAY 1.234043 (-1700 2850);
PAINT GREEN (-1700 2850);
DISPLAY INVISIBLE (-1700 2850);
FORCEPROP 1 LAST HDL_TAP TRUE
J 2
(-2025 2775);
DISPLAY 1.234043 (-2025 2775);
PAINT GREEN (-2025 2775);
DISPLAY INVISIBLE (-2025 2775);
FORCEPROP 1 LAST PATH I84
J 2
(-1700 2900);
DISPLAY 0.936170 (-1700 2900);
PAINT GREEN (-1700 2900);
DISPLAY INVISIBLE (-1700 2900);
FORCEADD TAP..6
R 2
(-1700 2850);
FORCEPROP 3 LASTPIN (-1750 2850) SIG_NAME M_M_DQ<25>
J 0
(-1740 2860);
DISPLAY 0.659574 (-1740 2860);
PAINT MONO (-1740 2860);
DISPLAY INVISIBLE (-1740 2860);
FORCEPROP 1 LASTPIN (-1750 2850) BN 25
J 2
(-1700 2860);
DISPLAY 0.617021 (-1700 2860);
PAINT PINK (-1700 2860);
FORCEPROP 2 LAST CDS_LIB mstr_standard
J 2
(-1700 2850);
DISPLAY 0.787234 (-1700 2850);
PAINT MONO (-1700 2850);
DISPLAY INVISIBLE (-1700 2850);
FORCEPROP 1 LAST BODY_TYPE PLUMBING
J 2
(-1700 2800);
DISPLAY 1.234043 (-1700 2800);
PAINT GREEN (-1700 2800);
DISPLAY INVISIBLE (-1700 2800);
FORCEPROP 1 LAST HDL_TAP TRUE
J 2
(-2025 2725);
DISPLAY 1.234043 (-2025 2725);
PAINT GREEN (-2025 2725);
DISPLAY INVISIBLE (-2025 2725);
FORCEPROP 1 LAST PATH I85
J 2
(-1700 2850);
DISPLAY 0.936170 (-1700 2850);
PAINT GREEN (-1700 2850);
DISPLAY INVISIBLE (-1700 2850);
FORCEADD TAP..6
R 2
(-1700 2800);
FORCEPROP 3 LASTPIN (-1750 2800) SIG_NAME M_M_DQ<24>
J 0
(-1740 2810);
DISPLAY 0.659574 (-1740 2810);
PAINT MONO (-1740 2810);
DISPLAY INVISIBLE (-1740 2810);
FORCEPROP 1 LASTPIN (-1750 2800) BN 24
J 2
(-1700 2810);
DISPLAY 0.617021 (-1700 2810);
PAINT PINK (-1700 2810);
FORCEPROP 2 LAST CDS_LIB mstr_standard
J 2
(-1700 2800);
DISPLAY 0.787234 (-1700 2800);
PAINT MONO (-1700 2800);
DISPLAY INVISIBLE (-1700 2800);
FORCEPROP 1 LAST BODY_TYPE PLUMBING
J 2
(-1700 2750);
DISPLAY 1.234043 (-1700 2750);
PAINT GREEN (-1700 2750);
DISPLAY INVISIBLE (-1700 2750);
FORCEPROP 1 LAST HDL_TAP TRUE
J 2
(-2025 2675);
DISPLAY 1.234043 (-2025 2675);
PAINT GREEN (-2025 2675);
DISPLAY INVISIBLE (-2025 2675);
FORCEPROP 1 LAST PATH I86
J 2
(-1700 2800);
DISPLAY 0.936170 (-1700 2800);
PAINT GREEN (-1700 2800);
DISPLAY INVISIBLE (-1700 2800);
FORCEADD SCONN288_H44441003..2
(0 4300);
FORCEPROP 1 LAST LOCATION J9L1
J 0
(-400 5400);
DISPLAY 0.617021 (-400 5400);
PAINT AQUA (-400 5400);
FORCEPROP 1 LAST PART_NUMBER H44441-003
J 0
(-400 3200);
DISPLAY 0.617021 (-400 3200);
PAINT BLUE (-400 3200);
FORCEPROP 1 LAST MATERIAL SCONN
J 0
(-400 5350);
DISPLAY 0.617021 (-400 5350);
PAINT SKYBLUE (-400 5350);
FORCEPROP 2 LASTPIN (450 5150) $PN 51
J 0
(460 5160);
DISPLAY 0.617021 (460 5160);
PAINT ORANGE (460 5160);
FORCEPROP 2 LASTPIN (450 5100) $PN 52
J 0
(460 5110);
DISPLAY 0.617021 (460 5110);
PAINT ORANGE (460 5110);
FORCEPROP 2 LASTPIN (450 5050) $PN 132
J 0
(460 5060);
DISPLAY 0.617021 (460 5060);
PAINT ORANGE (460 5060);
FORCEPROP 2 LASTPIN (450 5000) $PN 133
J 0
(460 5010);
DISPLAY 0.617021 (460 5010);
PAINT ORANGE (460 5010);
FORCEPROP 2 LASTPIN (450 4950) $PN 121
J 0
(460 4960);
DISPLAY 0.617021 (460 4960);
PAINT ORANGE (460 4960);
FORCEPROP 2 LASTPIN (450 4900) $PN 122
J 0
(460 4910);
DISPLAY 0.617021 (460 4910);
PAINT ORANGE (460 4910);
FORCEPROP 2 LASTPIN (450 4850) $PN 110
J 0
(460 4860);
DISPLAY 0.617021 (460 4860);
PAINT ORANGE (460 4860);
FORCEPROP 2 LASTPIN (450 4800) $PN 111
J 0
(460 4810);
DISPLAY 0.617021 (460 4810);
PAINT ORANGE (460 4810);
FORCEPROP 2 LASTPIN (450 4750) $PN 99
J 0
(460 4760);
DISPLAY 0.617021 (460 4760);
PAINT ORANGE (460 4760);
FORCEPROP 2 LASTPIN (450 4700) $PN 100
J 0
(460 4710);
DISPLAY 0.617021 (460 4710);
PAINT ORANGE (460 4710);
FORCEPROP 2 LASTPIN (450 4650) $PN 40
J 0
(460 4660);
DISPLAY 0.617021 (460 4660);
PAINT ORANGE (460 4660);
FORCEPROP 2 LASTPIN (450 4600) $PN 41
J 0
(460 4610);
DISPLAY 0.617021 (460 4610);
PAINT ORANGE (460 4610);
FORCEPROP 2 LASTPIN (450 4550) $PN 29
J 0
(460 4560);
DISPLAY 0.617021 (460 4560);
PAINT ORANGE (460 4560);
FORCEPROP 2 LASTPIN (450 4500) $PN 30
J 0
(460 4510);
DISPLAY 0.617021 (460 4510);
PAINT ORANGE (460 4510);
FORCEPROP 2 LASTPIN (450 4450) $PN 18
J 0
(460 4460);
DISPLAY 0.617021 (460 4460);
PAINT ORANGE (460 4460);
FORCEPROP 2 LASTPIN (450 4400) $PN 19
J 0
(460 4410);
DISPLAY 0.617021 (460 4410);
PAINT ORANGE (460 4410);
FORCEPROP 2 LASTPIN (450 4350) $PN 7
J 0
(460 4360);
DISPLAY 0.617021 (460 4360);
PAINT ORANGE (460 4360);
FORCEPROP 2 LASTPIN (450 4300) $PN 8
J 0
(460 4310);
DISPLAY 0.617021 (460 4310);
PAINT ORANGE (460 4310);
FORCEPROP 2 LASTPIN (450 4250) $PN 197
J 0
(460 4260);
DISPLAY 0.617021 (460 4260);
PAINT ORANGE (460 4260);
FORCEPROP 2 LASTPIN (450 4200) $PN 196
J 0
(460 4210);
DISPLAY 0.617021 (460 4210);
PAINT ORANGE (460 4210);
FORCEPROP 2 LASTPIN (450 4150) $PN 278
J 0
(460 4160);
DISPLAY 0.617021 (460 4160);
PAINT ORANGE (460 4160);
FORCEPROP 2 LASTPIN (450 4100) $PN 277
J 0
(460 4110);
DISPLAY 0.617021 (460 4110);
PAINT ORANGE (460 4110);
FORCEPROP 2 LASTPIN (450 4050) $PN 267
J 0
(460 4060);
DISPLAY 0.617021 (460 4060);
PAINT ORANGE (460 4060);
FORCEPROP 2 LASTPIN (450 4000) $PN 266
J 0
(460 4010);
DISPLAY 0.617021 (460 4010);
PAINT ORANGE (460 4010);
FORCEPROP 2 LASTPIN (450 3950) $PN 256
J 0
(460 3960);
DISPLAY 0.617021 (460 3960);
PAINT ORANGE (460 3960);
FORCEPROP 2 LASTPIN (450 3900) $PN 255
J 0
(460 3910);
DISPLAY 0.617021 (460 3910);
PAINT ORANGE (460 3910);
FORCEPROP 2 LASTPIN (450 3850) $PN 245
J 0
(460 3860);
DISPLAY 0.617021 (460 3860);
PAINT ORANGE (460 3860);
FORCEPROP 2 LASTPIN (450 3800) $PN 244
J 0
(460 3810);
DISPLAY 0.617021 (460 3810);
PAINT ORANGE (460 3810);
FORCEPROP 2 LASTPIN (450 3750) $PN 186
J 0
(460 3760);
DISPLAY 0.617021 (460 3760);
PAINT ORANGE (460 3760);
FORCEPROP 2 LASTPIN (450 3700) $PN 185
J 0
(460 3710);
DISPLAY 0.617021 (460 3710);
PAINT ORANGE (460 3710);
FORCEPROP 2 LASTPIN (450 3650) $PN 175
J 0
(460 3660);
DISPLAY 0.617021 (460 3660);
PAINT ORANGE (460 3660);
FORCEPROP 2 LASTPIN (450 3600) $PN 174
J 0
(460 3610);
DISPLAY 0.617021 (460 3610);
PAINT ORANGE (460 3610);
FORCEPROP 2 LASTPIN (450 3550) $PN 164
J 0
(460 3560);
DISPLAY 0.617021 (460 3560);
PAINT ORANGE (460 3560);
FORCEPROP 2 LASTPIN (450 3500) $PN 163
J 0
(460 3510);
DISPLAY 0.617021 (460 3510);
PAINT ORANGE (460 3510);
FORCEPROP 2 LASTPIN (450 3450) $PN 153
J 0
(460 3460);
DISPLAY 0.617021 (460 3460);
PAINT ORANGE (460 3460);
FORCEPROP 2 LASTPIN (450 3400) $PN 152
J 0
(460 3410);
DISPLAY 0.617021 (460 3410);
PAINT ORANGE (460 3410);
FORCEPROP 1 LAST PACK_TYPE PIP
J 0
(-400 5450);
PAINT SKYBLUE (-400 5450);
DISPLAY INVISIBLE (-400 5450);
FORCEPROP 2 LAST SEC_TYPE PIP
J 0
(-400 5450);
DISPLAY 1.021277 (-400 5450);
PAINT ORANGE (-400 5450);
DISPLAY INVISIBLE (-400 5450);
FORCEPROP 2 LAST CDS_LIB mstr_sconn
J 0
(0 4300);
PAINT ORANGE (0 4300);
DISPLAY INVISIBLE (0 4300);
FORCEPROP 2 LAST BOM_COST DDR4_CH_M
J 0
(0 4300);
PAINT ORANGE (0 4300);
DISPLAY INVISIBLE (0 4300);
FORCEPROP 2 LAST SEC 2
J 0
(-400 5450);
DISPLAY 0.680851 (-400 5450);
PAINT MONO (-400 5450);
DISPLAY INVISIBLE (-400 5450);
FORCEPROP 2 LAST CDS_LOCATION J9L1
J 0
(-400 5400);
DISPLAY 0.617021 (-400 5400);
PAINT AQUA (-400 5400);
DISPLAY INVISIBLE (-400 5400);
FORCEPROP 1 LAST PATH I87
J 0
(0 5350);
PAINT GREEN (0 5350);
DISPLAY INVISIBLE (0 5350);
FORCEPROP 2 LAST ROOM DDR4_CH_M
J 0
(-400 5500);
PAINT ORANGE (-400 5500);
DISPLAY INVISIBLE (-400 5500);
FORCEADD TAP..6
R 2
(-1700 2500);
FORCEPROP 3 LASTPIN (-1750 2500) SIG_NAME M_M_DQ<18>
J 0
(-1740 2510);
DISPLAY 0.659574 (-1740 2510);
PAINT MONO (-1740 2510);
DISPLAY INVISIBLE (-1740 2510);
FORCEPROP 1 LASTPIN (-1750 2500) BN 18
J 2
(-1700 2510);
DISPLAY 0.617021 (-1700 2510);
PAINT PINK (-1700 2510);
FORCEPROP 2 LAST CDS_LIB mstr_standard
J 2
(-1700 2500);
DISPLAY 0.787234 (-1700 2500);
PAINT MONO (-1700 2500);
DISPLAY INVISIBLE (-1700 2500);
FORCEPROP 1 LAST BODY_TYPE PLUMBING
J 2
(-1700 2450);
DISPLAY 1.234043 (-1700 2450);
PAINT GREEN (-1700 2450);
DISPLAY INVISIBLE (-1700 2450);
FORCEPROP 1 LAST HDL_TAP TRUE
J 2
(-2025 2375);
DISPLAY 1.234043 (-2025 2375);
PAINT GREEN (-2025 2375);
DISPLAY INVISIBLE (-2025 2375);
FORCEPROP 1 LAST PATH I88
J 2
(-1700 2500);
DISPLAY 0.936170 (-1700 2500);
PAINT GREEN (-1700 2500);
DISPLAY INVISIBLE (-1700 2500);
FORCEADD TAP..6
R 2
(-1700 2700);
FORCEPROP 3 LASTPIN (-1750 2700) SIG_NAME M_M_DQ<22>
J 0
(-1740 2710);
DISPLAY 0.659574 (-1740 2710);
PAINT MONO (-1740 2710);
DISPLAY INVISIBLE (-1740 2710);
FORCEPROP 1 LASTPIN (-1750 2700) BN 22
J 2
(-1700 2710);
DISPLAY 0.617021 (-1700 2710);
PAINT PINK (-1700 2710);
FORCEPROP 2 LAST CDS_LIB mstr_standard
J 2
(-1700 2700);
DISPLAY 0.787234 (-1700 2700);
PAINT MONO (-1700 2700);
DISPLAY INVISIBLE (-1700 2700);
FORCEPROP 1 LAST BODY_TYPE PLUMBING
J 2
(-1700 2650);
DISPLAY 1.234043 (-1700 2650);
PAINT GREEN (-1700 2650);
DISPLAY INVISIBLE (-1700 2650);
FORCEPROP 1 LAST HDL_TAP TRUE
J 2
(-2025 2575);
DISPLAY 1.234043 (-2025 2575);
PAINT GREEN (-2025 2575);
DISPLAY INVISIBLE (-2025 2575);
FORCEPROP 1 LAST PATH I89
J 2
(-1700 2700);
DISPLAY 0.936170 (-1700 2700);
PAINT GREEN (-1700 2700);
DISPLAY INVISIBLE (-1700 2700);
FORCEADD PVTT_KLM..1
(-1150 2700);
FORCEPROP 3 LASTPIN (-1150 2650) SIG_NAME PVTT_KLM\g
J 0
(-1140 2660);
DISPLAY 0.659574 (-1140 2660);
PAINT MONO (-1140 2660);
DISPLAY INVISIBLE (-1140 2660);
FORCEPROP 1 LAST VOLTAGE 0.6V
J 0
(-1195 2657);
DISPLAY 0.340426 (-1195 2657);
PAINT SKYBLUE (-1195 2657);
DISPLAY INVISIBLE (-1195 2657);
FORCEPROP 2 LAST BOM_COST PROC
J 0
(-1150 2705);
PAINT ORANGE (-1150 2705);
DISPLAY INVISIBLE (-1150 2705);
FORCEPROP 2 LAST CDS_LIB mstr_symbols
J 0
(-1150 2700);
PAINT ORANGE (-1150 2700);
DISPLAY INVISIBLE (-1150 2700);
FORCEPROP 1 LAST BODY_TYPE PLUMBING
J 0
(-1195 2657);
DISPLAY 0.340426 (-1195 2657);
PAINT GREEN (-1195 2657);
DISPLAY INVISIBLE (-1195 2657);
FORCEPROP 1 LAST PATH I9
J 0
(-1100 2725);
DISPLAY 0.872340 (-1100 2725);
PAINT AQUA (-1100 2725);
DISPLAY INVISIBLE (-1100 2725);
FORCEPROP 2 LAST ROOM PROC
J 0
(-1150 2800);
DISPLAY 0.787234 (-1150 2800);
PAINT ORANGE (-1150 2800);
DISPLAY INVISIBLE (-1150 2800);
FORCEPROP 1 LAST HDL_POWER PVTT_KLM
J 1
(-1150 2750);
DISPLAY 0.872340 (-1150 2750);
PAINT GREEN (-1150 2750);
DISPLAY INVISIBLE (-1150 2750);
FORCEADD TAP..6
R 2
(-1700 2650);
FORCEPROP 3 LASTPIN (-1750 2650) SIG_NAME M_M_DQ<21>
J 0
(-1740 2660);
DISPLAY 0.659574 (-1740 2660);
PAINT MONO (-1740 2660);
DISPLAY INVISIBLE (-1740 2660);
FORCEPROP 1 LASTPIN (-1750 2650) BN 21
J 2
(-1700 2660);
DISPLAY 0.617021 (-1700 2660);
PAINT PINK (-1700 2660);
FORCEPROP 2 LAST CDS_LIB mstr_standard
J 2
(-1700 2650);
DISPLAY 0.787234 (-1700 2650);
PAINT MONO (-1700 2650);
DISPLAY INVISIBLE (-1700 2650);
FORCEPROP 1 LAST BODY_TYPE PLUMBING
J 2
(-1700 2600);
DISPLAY 1.234043 (-1700 2600);
PAINT GREEN (-1700 2600);
DISPLAY INVISIBLE (-1700 2600);
FORCEPROP 1 LAST HDL_TAP TRUE
J 2
(-2025 2525);
DISPLAY 1.234043 (-2025 2525);
PAINT GREEN (-2025 2525);
DISPLAY INVISIBLE (-2025 2525);
FORCEPROP 1 LAST PATH I90
J 2
(-1700 2650);
DISPLAY 0.936170 (-1700 2650);
PAINT GREEN (-1700 2650);
DISPLAY INVISIBLE (-1700 2650);
FORCEADD TAP..6
R 2
(-1700 2550);
FORCEPROP 3 LASTPIN (-1750 2550) SIG_NAME M_M_DQ<19>
J 0
(-1740 2560);
DISPLAY 0.659574 (-1740 2560);
PAINT MONO (-1740 2560);
DISPLAY INVISIBLE (-1740 2560);
FORCEPROP 1 LASTPIN (-1750 2550) BN 19
J 2
(-1700 2560);
DISPLAY 0.617021 (-1700 2560);
PAINT PINK (-1700 2560);
FORCEPROP 2 LAST CDS_LIB mstr_standard
J 2
(-1700 2550);
DISPLAY 0.787234 (-1700 2550);
PAINT MONO (-1700 2550);
DISPLAY INVISIBLE (-1700 2550);
FORCEPROP 1 LAST BODY_TYPE PLUMBING
J 2
(-1700 2500);
DISPLAY 1.234043 (-1700 2500);
PAINT GREEN (-1700 2500);
DISPLAY INVISIBLE (-1700 2500);
FORCEPROP 1 LAST HDL_TAP TRUE
J 2
(-2025 2425);
DISPLAY 1.234043 (-2025 2425);
PAINT GREEN (-2025 2425);
DISPLAY INVISIBLE (-2025 2425);
FORCEPROP 1 LAST PATH I91
J 2
(-1700 2550);
DISPLAY 0.936170 (-1700 2550);
PAINT GREEN (-1700 2550);
DISPLAY INVISIBLE (-1700 2550);
FORCEADD TAP..6
R 2
(-1700 2600);
FORCEPROP 3 LASTPIN (-1750 2600) SIG_NAME M_M_DQ<20>
J 0
(-1740 2610);
DISPLAY 0.659574 (-1740 2610);
PAINT MONO (-1740 2610);
DISPLAY INVISIBLE (-1740 2610);
FORCEPROP 1 LASTPIN (-1750 2600) BN 20
J 2
(-1700 2610);
DISPLAY 0.617021 (-1700 2610);
PAINT PINK (-1700 2610);
FORCEPROP 2 LAST CDS_LIB mstr_standard
J 2
(-1700 2600);
DISPLAY 0.787234 (-1700 2600);
PAINT MONO (-1700 2600);
DISPLAY INVISIBLE (-1700 2600);
FORCEPROP 1 LAST BODY_TYPE PLUMBING
J 2
(-1700 2550);
DISPLAY 1.234043 (-1700 2550);
PAINT GREEN (-1700 2550);
DISPLAY INVISIBLE (-1700 2550);
FORCEPROP 1 LAST HDL_TAP TRUE
J 2
(-2025 2475);
DISPLAY 1.234043 (-2025 2475);
PAINT GREEN (-2025 2475);
DISPLAY INVISIBLE (-2025 2475);
FORCEPROP 1 LAST PATH I92
J 2
(-1700 2600);
DISPLAY 0.936170 (-1700 2600);
PAINT GREEN (-1700 2600);
DISPLAY INVISIBLE (-1700 2600);
FORCEADD TAP..6
R 2
(-1700 2250);
FORCEPROP 3 LASTPIN (-1750 2250) SIG_NAME M_M_DQ<13>
J 0
(-1740 2260);
DISPLAY 0.659574 (-1740 2260);
PAINT MONO (-1740 2260);
DISPLAY INVISIBLE (-1740 2260);
FORCEPROP 1 LASTPIN (-1750 2250) BN 13
J 2
(-1700 2260);
DISPLAY 0.617021 (-1700 2260);
PAINT PINK (-1700 2260);
FORCEPROP 2 LAST CDS_LIB mstr_standard
J 2
(-1700 2250);
DISPLAY 0.787234 (-1700 2250);
PAINT MONO (-1700 2250);
DISPLAY INVISIBLE (-1700 2250);
FORCEPROP 1 LAST BODY_TYPE PLUMBING
J 2
(-1700 2200);
DISPLAY 1.234043 (-1700 2200);
PAINT GREEN (-1700 2200);
DISPLAY INVISIBLE (-1700 2200);
FORCEPROP 1 LAST HDL_TAP TRUE
J 2
(-2025 2125);
DISPLAY 1.234043 (-2025 2125);
PAINT GREEN (-2025 2125);
DISPLAY INVISIBLE (-2025 2125);
FORCEPROP 1 LAST PATH I93
J 2
(-1700 2250);
DISPLAY 0.936170 (-1700 2250);
PAINT GREEN (-1700 2250);
DISPLAY INVISIBLE (-1700 2250);
FORCEADD TAP..6
R 2
(-1700 2400);
FORCEPROP 3 LASTPIN (-1750 2400) SIG_NAME M_M_DQ<16>
J 0
(-1740 2410);
DISPLAY 0.659574 (-1740 2410);
PAINT MONO (-1740 2410);
DISPLAY INVISIBLE (-1740 2410);
FORCEPROP 1 LASTPIN (-1750 2400) BN 16
J 2
(-1700 2410);
DISPLAY 0.617021 (-1700 2410);
PAINT PINK (-1700 2410);
FORCEPROP 2 LAST CDS_LIB mstr_standard
J 2
(-1700 2400);
DISPLAY 0.787234 (-1700 2400);
PAINT MONO (-1700 2400);
DISPLAY INVISIBLE (-1700 2400);
FORCEPROP 1 LAST BODY_TYPE PLUMBING
J 2
(-1700 2350);
DISPLAY 1.234043 (-1700 2350);
PAINT GREEN (-1700 2350);
DISPLAY INVISIBLE (-1700 2350);
FORCEPROP 1 LAST HDL_TAP TRUE
J 2
(-2025 2275);
DISPLAY 1.234043 (-2025 2275);
PAINT GREEN (-2025 2275);
DISPLAY INVISIBLE (-2025 2275);
FORCEPROP 1 LAST PATH I94
J 2
(-1700 2400);
DISPLAY 0.936170 (-1700 2400);
PAINT GREEN (-1700 2400);
DISPLAY INVISIBLE (-1700 2400);
FORCEADD TAP..6
R 2
(-1700 2450);
FORCEPROP 3 LASTPIN (-1750 2450) SIG_NAME M_M_DQ<17>
J 0
(-1740 2460);
DISPLAY 0.659574 (-1740 2460);
PAINT MONO (-1740 2460);
DISPLAY INVISIBLE (-1740 2460);
FORCEPROP 1 LASTPIN (-1750 2450) BN 17
J 2
(-1700 2460);
DISPLAY 0.617021 (-1700 2460);
PAINT PINK (-1700 2460);
FORCEPROP 2 LAST CDS_LIB mstr_standard
J 2
(-1700 2450);
DISPLAY 0.787234 (-1700 2450);
PAINT MONO (-1700 2450);
DISPLAY INVISIBLE (-1700 2450);
FORCEPROP 1 LAST BODY_TYPE PLUMBING
J 2
(-1700 2400);
DISPLAY 1.234043 (-1700 2400);
PAINT GREEN (-1700 2400);
DISPLAY INVISIBLE (-1700 2400);
FORCEPROP 1 LAST HDL_TAP TRUE
J 2
(-2025 2325);
DISPLAY 1.234043 (-2025 2325);
PAINT GREEN (-2025 2325);
DISPLAY INVISIBLE (-2025 2325);
FORCEPROP 1 LAST PATH I95
J 2
(-1700 2450);
DISPLAY 0.936170 (-1700 2450);
PAINT GREEN (-1700 2450);
DISPLAY INVISIBLE (-1700 2450);
FORCEADD TAP..6
R 2
(-1700 2300);
FORCEPROP 3 LASTPIN (-1750 2300) SIG_NAME M_M_DQ<14>
J 0
(-1740 2310);
DISPLAY 0.659574 (-1740 2310);
PAINT MONO (-1740 2310);
DISPLAY INVISIBLE (-1740 2310);
FORCEPROP 1 LASTPIN (-1750 2300) BN 14
J 2
(-1700 2310);
DISPLAY 0.617021 (-1700 2310);
PAINT PINK (-1700 2310);
FORCEPROP 2 LAST CDS_LIB mstr_standard
J 2
(-1700 2300);
DISPLAY 0.787234 (-1700 2300);
PAINT MONO (-1700 2300);
DISPLAY INVISIBLE (-1700 2300);
FORCEPROP 1 LAST BODY_TYPE PLUMBING
J 2
(-1700 2250);
DISPLAY 1.234043 (-1700 2250);
PAINT GREEN (-1700 2250);
DISPLAY INVISIBLE (-1700 2250);
FORCEPROP 1 LAST HDL_TAP TRUE
J 2
(-2025 2175);
DISPLAY 1.234043 (-2025 2175);
PAINT GREEN (-2025 2175);
DISPLAY INVISIBLE (-2025 2175);
FORCEPROP 1 LAST PATH I96
J 2
(-1700 2300);
DISPLAY 0.936170 (-1700 2300);
PAINT GREEN (-1700 2300);
DISPLAY INVISIBLE (-1700 2300);
FORCEADD TAP..6
R 2
(-1700 2350);
FORCEPROP 3 LASTPIN (-1750 2350) SIG_NAME M_M_DQ<15>
J 0
(-1740 2360);
DISPLAY 0.659574 (-1740 2360);
PAINT MONO (-1740 2360);
DISPLAY INVISIBLE (-1740 2360);
FORCEPROP 1 LASTPIN (-1750 2350) BN 15
J 2
(-1700 2360);
DISPLAY 0.617021 (-1700 2360);
PAINT PINK (-1700 2360);
FORCEPROP 2 LAST CDS_LIB mstr_standard
J 2
(-1700 2350);
DISPLAY 0.787234 (-1700 2350);
PAINT MONO (-1700 2350);
DISPLAY INVISIBLE (-1700 2350);
FORCEPROP 1 LAST BODY_TYPE PLUMBING
J 2
(-1700 2300);
DISPLAY 1.234043 (-1700 2300);
PAINT GREEN (-1700 2300);
DISPLAY INVISIBLE (-1700 2300);
FORCEPROP 1 LAST HDL_TAP TRUE
J 2
(-2025 2225);
DISPLAY 1.234043 (-2025 2225);
PAINT GREEN (-2025 2225);
DISPLAY INVISIBLE (-2025 2225);
FORCEPROP 1 LAST PATH I97
J 2
(-1700 2350);
DISPLAY 0.936170 (-1700 2350);
PAINT GREEN (-1700 2350);
DISPLAY INVISIBLE (-1700 2350);
FORCEADD TAP..6
R 2
(-1700 2000);
FORCEPROP 3 LASTPIN (-1750 2000) SIG_NAME M_M_DQ<8>
J 0
(-1740 2010);
DISPLAY 0.659574 (-1740 2010);
PAINT MONO (-1740 2010);
DISPLAY INVISIBLE (-1740 2010);
FORCEPROP 1 LASTPIN (-1750 2000) BN 8
J 2
(-1700 2010);
DISPLAY 0.617021 (-1700 2010);
PAINT PINK (-1700 2010);
FORCEPROP 2 LAST CDS_LIB mstr_standard
J 2
(-1700 2000);
DISPLAY 0.787234 (-1700 2000);
PAINT MONO (-1700 2000);
DISPLAY INVISIBLE (-1700 2000);
FORCEPROP 1 LAST BODY_TYPE PLUMBING
J 2
(-1700 1950);
DISPLAY 1.234043 (-1700 1950);
PAINT GREEN (-1700 1950);
DISPLAY INVISIBLE (-1700 1950);
FORCEPROP 1 LAST HDL_TAP TRUE
J 2
(-2025 1875);
DISPLAY 1.234043 (-2025 1875);
PAINT GREEN (-2025 1875);
DISPLAY INVISIBLE (-2025 1875);
FORCEPROP 1 LAST PATH I98
J 2
(-1700 2000);
DISPLAY 0.936170 (-1700 2000);
PAINT GREEN (-1700 2000);
DISPLAY INVISIBLE (-1700 2000);
FORCEADD TAP..6
R 2
(-1700 2100);
FORCEPROP 3 LASTPIN (-1750 2100) SIG_NAME M_M_DQ<10>
J 0
(-1740 2110);
DISPLAY 0.659574 (-1740 2110);
PAINT MONO (-1740 2110);
DISPLAY INVISIBLE (-1740 2110);
FORCEPROP 1 LASTPIN (-1750 2100) BN 10
J 2
(-1700 2110);
DISPLAY 0.617021 (-1700 2110);
PAINT PINK (-1700 2110);
FORCEPROP 2 LAST CDS_LIB mstr_standard
J 2
(-1700 2100);
DISPLAY 0.787234 (-1700 2100);
PAINT MONO (-1700 2100);
DISPLAY INVISIBLE (-1700 2100);
FORCEPROP 1 LAST BODY_TYPE PLUMBING
J 2
(-1700 2050);
DISPLAY 1.234043 (-1700 2050);
PAINT GREEN (-1700 2050);
DISPLAY INVISIBLE (-1700 2050);
FORCEPROP 1 LAST HDL_TAP TRUE
J 2
(-2025 1975);
DISPLAY 1.234043 (-2025 1975);
PAINT GREEN (-2025 1975);
DISPLAY INVISIBLE (-2025 1975);
FORCEPROP 1 LAST PATH I99
J 2
(-1700 2100);
DISPLAY 0.936170 (-1700 2100);
PAINT GREEN (-1700 2100);
DISPLAY INVISIBLE (-1700 2100);
FORCEADD BOM_NOTE..1
(-5025 5300);
FORCEPROP 0 LAST L1 UNSTUFF FOR SKU B
J 0
(-5175 5200);
DISPLAY 1.063830 (-5175 5200);
PAINT WHITE (-5175 5200);
FORCEPROP 2 LAST BOM_COST SB
J 0
(-5175 5275);
DISPLAY 1.361702 (-5175 5275);
PAINT ORANGE (-5175 5275);
DISPLAY INVISIBLE (-5175 5275);
FORCEPROP 2 LAST CDS_LIB mstr_symbols
J 0
(-5025 5300);
PAINT ORANGE (-5025 5300);
DISPLAY INVISIBLE (-5025 5300);
FORCEPROP 1 LAST COMMENT_BODY TRUE
J 0
(-5000 5400);
DISPLAY 1.319149 (-5000 5400);
PAINT ORANGE (-5000 5400);
DISPLAY INVISIBLE (-5000 5400);
FORCEPROP 2 LAST ROOM SB_HEADERS
J 0
(-5175 5275);
DISPLAY 1.361702 (-5175 5275);
PAINT ORANGE (-5175 5275);
DISPLAY INVISIBLE (-5175 5275);
FORCEADD INTEL_CORP_BPAGE..1
(2650 500);
FORCEPROP 1 LAST CDS_CON_LAST_MODIFIED Tue Dec 01 11:51:46 2015
J 0
(1225 825);
DISPLAY 0.787234 (1225 825);
PAINT ORANGE (1225 825);
DISPLAY INVISIBLE (1225 825);
FORCEPROP 1 LAST CUSTOM_TXT_CDS <CURRENT_DESIGN_SHEET> OF <TOTAL_DESIGN_SHEETS>
J 0
(2150 525);
PAINT GREEN (2150 525);
FORCEPROP 1 LAST CUSTOM_TXT_CDS <CON_LAST_MODIFIED>
J 0
(725 850);
PAINT GREEN (725 850);
FORCEPROP 2 LAST CUSTOM_TXT_CDS <XR_PAGE_TITLE>
J 0
(-5240 5750);
DISPLAY 0.638298 (-5240 5750);
PAINT PINK (-5240 5750);
DISPLAY INVISIBLE (-5240 5750);
FORCEPROP 1 LAST SCH_ADDRESS3 Santa Clara, CA 95052-8119
J 0
(-1325 525);
DISPLAY 0.617021 (-1325 525);
PAINT GREEN (-1325 525);
FORCEPROP 1 LAST SCH_ADDRESS2 P.O. BOX 58119
J 0
(-1325 575);
DISPLAY 0.617021 (-1325 575);
PAINT GREEN (-1325 575);
FORCEPROP 1 LAST SCH_ADDRESS1 2200 Mission College Blvd.
J 0
(-1325 625);
DISPLAY 0.617021 (-1325 625);
PAINT GREEN (-1325 625);
FORCEPROP 1 LAST SCH_TITLE CPU1 DDR4 CH M DIMM1
J 0
(-5300 550);
DISPLAY 1.212766 (-5300 550);
PAINT WHITE (-5300 550);
FORCEPROP 1 LAST SCH_NUMBER H4694802
J 0
(1350 650);
DISPLAY 1.212766 (1350 650);
PAINT YELLOW (1350 650);
FORCEPROP 1 LAST SCH_DEPT BESD
J 1
(-1800 600);
DISPLAY 1.212766 (-1800 600);
PAINT YELLOW (-1800 600);
FORCEPROP 1 LAST SCH_REV 2.420
J 0
(2400 650);
DISPLAY 0.978723 (2400 650);
PAINT YELLOW (2400 650);
FORCEPROP 2 LAST PAGE_BORDER TRUE
J 0
(-5240 5750);
DISPLAY 0.680851 (-5240 5750);
PAINT PINK (-5240 5750);
DISPLAY INVISIBLE (-5240 5750);
FORCEPROP 2 LAST CDS_LIB mstr_symbols
J 0
(2650 500);
DISPLAY 0.787234 (2650 500);
PAINT MONO (2650 500);
DISPLAY INVISIBLE (2650 500);
FORCEPROP 1 LAST COMMENT_BODY TRUE
J 0
(2660 510);
DISPLAY 0.382979 (2660 510);
PAINT GREEN (2660 510);
DISPLAY INVISIBLE (2660 510);
FORCEPROP 2 LAST CDS_XR_PAGE_TITLE CR-88 : @BASEBOARD_FAB2_LIB.BASEBOARD_FAB2(SCH_1):PAGE88
J 0
(-5240 5750);
DISPLAY 0.638298 (-5240 5750);
PAINT PINK (-5240 5750);
DISPLAY INVISIBLE (-5240 5750);
WIRE 17 -1 (750 5175)(750 5200);
WIRE 17 -1 (750 5075)(750 5175);
WIRE 17 -1 (1550 5200)(750 5200);
FORCEPROP 2 LAST SIG_NAME M_M_DQS_DP<17:0>
J 0
(1000 5210);
DISPLAY 0.617021 (1000 5210);
PAINT ORANGE (1000 5210);
WIRE 17 -1 (750 4375)(750 4475);
WIRE 17 -1 (750 4275)(750 4375);
WIRE 17 -1 (750 4475)(750 4575);
WIRE 17 -1 (750 4575)(750 4675);
WIRE 17 -1 (750 4175)(750 4275);
WIRE 17 -1 (750 4075)(750 4175);
WIRE 17 -1 (750 4675)(750 4775);
WIRE 17 -1 (750 4775)(750 4875);
WIRE 17 -1 (750 3975)(750 4075);
WIRE 17 -1 (750 3875)(750 3975);
WIRE 17 -1 (750 4875)(750 4975);
WIRE 17 -1 (750 4975)(750 5075);
WIRE 17 -1 (750 3775)(750 3875);
WIRE 17 -1 (750 3675)(750 3775);
WIRE 17 -1 (750 3575)(750 3675);
WIRE 17 -1 (750 3475)(750 3575);
WIRE 17 -1 (950 4325)(950 4425);
WIRE 17 -1 (950 4225)(950 4325);
WIRE 17 -1 (950 4425)(950 4525);
WIRE 17 -1 (950 4525)(950 4625);
WIRE 17 -1 (950 4125)(950 4225);
WIRE 17 -1 (950 4025)(950 4125);
WIRE 17 -1 (950 4625)(950 4725);
WIRE 17 -1 (950 4725)(950 4825);
WIRE 17 -1 (950 3925)(950 4025);
WIRE 17 -1 (950 3825)(950 3925);
WIRE 17 -1 (950 4825)(950 4925);
WIRE 17 -1 (950 4925)(950 5025);
WIRE 17 -1 (950 3725)(950 3825);
WIRE 17 -1 (950 3625)(950 3725);
WIRE 17 -1 (950 5025)(950 5125);
WIRE 17 -1 (950 5125)(950 5150);
WIRE 17 -1 (950 3525)(950 3625);
WIRE 17 -1 (950 3425)(950 3525);
WIRE 17 -1 (1550 5150)(950 5150);
FORCEPROP 2 LAST SIG_NAME M_M_DQS_DN<17:0>
J 0
(1000 5160);
DISPLAY 0.617021 (1000 5160);
PAINT ORANGE (1000 5160);
WIRE 17 -1 (-1650 4800)(-1650 4775);
WIRE 17 -1 (-1200 4800)(-1650 4800);
FORCEPROP 2 LAST SIG_NAME M_M_DQ<63:0>
J 0
(-1610 4810);
DISPLAY 0.617021 (-1610 4810);
PAINT ORANGE (-1610 4810);
WIRE 17 -1 (-1650 4675)(-1650 4725);
WIRE 17 -1 (-1650 4625)(-1650 4675);
WIRE 17 -1 (-1650 4725)(-1650 4775);
WIRE 17 -1 (-1650 4575)(-1650 4625);
WIRE 17 -1 (-1650 4525)(-1650 4575);
WIRE 17 -1 (-1650 4475)(-1650 4525);
WIRE 17 -1 (-1650 4425)(-1650 4475);
WIRE 17 -1 (-1650 4375)(-1650 4425);
WIRE 17 -1 (-1650 4325)(-1650 4375);
WIRE 17 -1 (-1650 4275)(-1650 4325);
WIRE 17 -1 (-1650 4225)(-1650 4275);
WIRE 17 -1 (-1650 4175)(-1650 4225);
WIRE 17 -1 (-1650 4125)(-1650 4175);
WIRE 17 -1 (-1650 4075)(-1650 4125);
WIRE 17 -1 (-1650 4025)(-1650 4075);
WIRE 17 -1 (-1650 3975)(-1650 4025);
WIRE 17 -1 (-1650 3925)(-1650 3975);
WIRE 17 -1 (-1650 3875)(-1650 3925);
WIRE 17 -1 (-1650 3825)(-1650 3875);
WIRE 17 -1 (-1650 3775)(-1650 3825);
WIRE 17 -1 (-1650 3725)(-1650 3775);
WIRE 17 -1 (-1650 3675)(-1650 3725);
WIRE 17 -1 (-1650 3625)(-1650 3675);
WIRE 17 -1 (-1650 3575)(-1650 3625);
WIRE 17 -1 (-1650 3525)(-1650 3575);
WIRE 17 -1 (-1650 3475)(-1650 3525);
WIRE 17 -1 (-3250 4125)(-3250 4175);
WIRE 17 -1 (-3250 4075)(-3250 4125);
WIRE 17 -1 (-3250 4175)(-3250 4225);
WIRE 17 -1 (-3250 4225)(-3250 4275);
WIRE 17 -1 (-3250 4025)(-3250 4075);
WIRE 17 -1 (-3250 3975)(-3250 4025);
WIRE 17 -1 (-3250 4275)(-3250 4325);
WIRE 17 -1 (-3250 4325)(-3250 4375);
WIRE 17 -1 (-3250 3925)(-3250 3975);
WIRE 17 -1 (-3250 4375)(-3250 4425);
WIRE 17 -1 (-3250 4425)(-3250 4475);
WIRE 17 -1 (-3250 4475)(-3250 4525);
WIRE 17 -1 (-3250 4525)(-3250 4575);
WIRE 17 -1 (-3250 4575)(-3250 4625);
WIRE 17 -1 (-3250 4625)(-3250 4675);
WIRE 17 -1 (-3250 4675)(-3250 4725);
WIRE 17 -1 (-3250 4725)(-3250 4775);
WIRE 17 -1 (-3250 4775)(-3250 4800);
WIRE 17 -1 (-3750 4800)(-3250 4800);
FORCEPROP 2 LAST SIG_NAME M_M_MA<17:0>
J 0
(-3725 4810);
DISPLAY 0.617021 (-3725 4810);
PAINT ORANGE (-3725 4810);
WIRE 17 -1 (-1650 3425)(-1650 3475);
WIRE 17 -1 (-1650 3375)(-1650 3425);
WIRE 17 -1 (-1650 3325)(-1650 3375);
WIRE 17 -1 (-1650 3275)(-1650 3325);
WIRE 17 -1 (-1650 3225)(-1650 3275);
WIRE 17 -1 (-1650 3175)(-1650 3225);
WIRE 17 -1 (-1650 3125)(-1650 3175);
WIRE 17 -1 (-1650 3075)(-1650 3125);
WIRE 17 -1 (-1650 3025)(-1650 3075);
WIRE 17 -1 (-1650 2975)(-1650 3025);
WIRE 17 -1 (-1650 2925)(-1650 2975);
WIRE 17 -1 (-1650 2875)(-1650 2925);
WIRE 17 -1 (-1650 2825)(-1650 2875);
WIRE 17 -1 (-1650 2775)(-1650 2825);
WIRE 17 -1 (-1650 2725)(-1650 2775);
WIRE 17 -1 (-1650 2675)(-1650 2725);
WIRE 17 -1 (-1650 2625)(-1650 2675);
WIRE 17 -1 (-1650 2575)(-1650 2625);
WIRE 17 -1 (-1650 2525)(-1650 2575);
WIRE 17 -1 (-1650 2475)(-1650 2525);
WIRE 17 -1 (-1650 2425)(-1650 2475);
WIRE 17 -1 (-1650 2375)(-1650 2425);
WIRE 17 -1 (-1650 2325)(-1650 2375);
WIRE 17 -1 (-1650 2275)(-1650 2325);
WIRE 17 -1 (-1650 2225)(-1650 2275);
WIRE 17 -1 (-1650 2175)(-1650 2225);
WIRE 17 -1 (-1650 2125)(-1650 2175);
WIRE 17 -1 (-1650 2075)(-1650 2125);
WIRE 17 -1 (-1650 2025)(-1650 2075);
WIRE 17 -1 (-1650 1975)(-1650 2025);
WIRE 17 -1 (-1650 1925)(-1650 1975);
WIRE 17 -1 (-1650 1875)(-1650 1925);
WIRE 17 -1 (-1650 1825)(-1650 1875);
WIRE 17 -1 (-1650 1775)(-1650 1825);
WIRE 17 -1 (-1650 1725)(-1650 1775);
WIRE 17 -1 (-1650 1675)(-1650 1725);
WIRE 17 -1 (-1650 1625)(-1650 1675);
WIRE 17 -1 (-3850 3425)(-3850 3525);
WIRE 17 -1 (-3850 3525)(-3850 3600);
WIRE 17 -1 (-3850 3600)(-4350 3600);
FORCEPROP 2 LAST SIG_NAME M_M_CLK_DN<3:0>
J 0
(-4325 3610);
DISPLAY 0.617021 (-4325 3610);
PAINT ORANGE (-4325 3610);
WIRE 17 -1 (-3700 3650)(-3700 3575);
WIRE 17 -1 (-3700 3650)(-4350 3650);
FORCEPROP 2 LAST SIG_NAME M_M_CLK_DP<3:0>
J 0
(-4325 3660);
DISPLAY 0.617021 (-4325 3660);
PAINT ORANGE (-4325 3660);
WIRE 17 -1 (-3700 3575)(-3700 3475);
WIRE 17 -1 (-3250 3125)(-3250 3175);
WIRE 17 -1 (-3250 3175)(-3250 3225);
WIRE 17 -1 (-3250 3225)(-3250 3275);
WIRE 17 -1 (-3250 3275)(-3750 3275);
FORCEPROP 2 LAST SIG_NAME M_M_CS_N<7:0>
J 0
(-3725 3285);
DISPLAY 0.617021 (-3725 3285);
PAINT ORANGE (-3725 3285);
WIRE 17 -1 (-3250 2975)(-3250 3025);
WIRE 17 -1 (-3250 3050)(-3250 3025);
WIRE 17 -1 (-3250 3050)(-3750 3050);
FORCEPROP 2 LAST SIG_NAME M_M_CKE<3:0>
J 0
(-3725 3060);
DISPLAY 0.617021 (-3725 3060);
PAINT ORANGE (-3725 3060);
WIRE 17 -1 (-3250 2900)(-3250 2875);
WIRE 17 -1 (-3250 2900)(-3750 2900);
FORCEPROP 2 LAST SIG_NAME M_M_ODT<3:0>
J 0
(-3725 2910);
DISPLAY 0.617021 (-3725 2910);
PAINT ORANGE (-3725 2910);
WIRE 17 -1 (-3250 2825)(-3250 2875);
WIRE 17 -1 (-3250 2750)(-3250 2725);
WIRE 17 -1 (-3250 2750)(-3750 2750);
FORCEPROP 2 LAST SIG_NAME M_M_ECC<7:0>
J 0
(-3725 2760);
DISPLAY 0.617021 (-3725 2760);
PAINT ORANGE (-3725 2760);
WIRE 17 -1 (-3250 3775)(-3250 3825);
WIRE 17 -1 (-3250 3850)(-3250 3825);
WIRE 17 -1 (-3250 3850)(-3750 3850);
FORCEPROP 2 LAST SIG_NAME M_M_BA<1:0>
J 0
(-3725 3860);
DISPLAY 0.617021 (-3725 3860);
PAINT ORANGE (-3725 3860);
WIRE 17 -1 (-3250 3750)(-3250 3725);
WIRE 17 -1 (-3250 3750)(-3750 3750);
FORCEPROP 2 LAST SIG_NAME M_M_BG<1:0>
J 0
(-3725 3760);
DISPLAY 0.617021 (-3725 3760);
PAINT ORANGE (-3725 3760);
WIRE 17 -1 (-3250 3675)(-3250 3725);
WIRE 17 -1 (-3250 2375)(-3250 2425);
WIRE 17 -1 (-3250 2425)(-3250 2475);
WIRE 17 -1 (-3250 2475)(-3250 2525);
WIRE 17 -1 (-3250 2525)(-3250 2575);
WIRE 17 -1 (-3250 2575)(-3250 2625);
WIRE 17 -1 (-3250 2625)(-3250 2675);
WIRE 17 -1 (-3250 2675)(-3250 2725);
WIRE 16 -1 (-1000 1150)(-800 1150);
WIRE 16 -1 (-1000 1150)(-1000 1200);
WIRE 16 -1 (-1000 1200)(-800 1200);
WIRE 16 -1 (-1000 1200)(-1000 1250);
WIRE 16 -1 (-1000 1250)(-1000 1300);
WIRE 16 -1 (-1000 1250)(-800 1250);
WIRE 16 -1 (-1000 1300)(-800 1300);
WIRE 16 -1 (-1000 1300)(-1000 1350);
WIRE 16 -1 (-1000 1350)(-800 1350);
WIRE 16 -1 (-1000 1350)(-1000 1400);
WIRE 16 -1 (-1000 1400)(-800 1400);
WIRE 16 -1 (-1000 1400)(-1000 1450);
WIRE 16 -1 (-1000 1450)(-800 1450);
WIRE 16 -1 (-1000 1450)(-1000 1500);
WIRE 16 -1 (-1000 1500)(-1000 1550);
WIRE 16 -1 (-1000 1500)(-800 1500);
WIRE 16 -1 (-1000 1550)(-800 1550);
WIRE 16 -1 (-1000 1550)(-1000 1600);
WIRE 16 -1 (-1000 1600)(-800 1600);
WIRE 16 -1 (-1000 1600)(-1000 1650);
WIRE 16 -1 (-1000 1650)(-800 1650);
WIRE 16 -1 (-1000 1650)(-1000 1700);
WIRE 16 -1 (-1000 1700)(-800 1700);
WIRE 16 -1 (-1000 1700)(-1000 1750);
WIRE 16 -1 (-1000 1750)(-1000 1800);
WIRE 16 -1 (-1000 1750)(-800 1750);
WIRE 16 -1 (-1000 1800)(-800 1800);
WIRE 16 -1 (-1000 1800)(-1000 1850);
WIRE 16 -1 (-1000 1850)(-800 1850);
WIRE 16 -1 (-1000 1850)(-1000 1900);
WIRE 16 -1 (-1000 1900)(-800 1900);
WIRE 16 -1 (-1000 1900)(-1000 1950);
WIRE 16 -1 (-1000 1950)(-800 1950);
WIRE 16 -1 (-1000 1950)(-1000 2000);
WIRE 16 -1 (-1000 2000)(-1000 2050);
WIRE 16 -1 (-1000 2000)(-800 2000);
WIRE 16 -1 (-1000 2050)(-800 2050);
WIRE 16 -1 (-1000 2050)(-1000 2100);
WIRE 16 -1 (-1000 2100)(-800 2100);
WIRE 16 -1 (-1000 2100)(-1000 2150);
WIRE 16 -1 (-1000 2150)(-800 2150);
WIRE 16 -1 (-1000 2150)(-1000 2200);
WIRE 16 -1 (-1000 2200)(-800 2200);
WIRE 16 -1 (-1000 2200)(-1000 2250);
WIRE 16 -1 (-1000 2250)(-800 2250);
WIRE 16 -1 (-1000 2250)(-1000 2300);
WIRE 16 -1 (-1000 2300)(-1000 2350);
WIRE 16 -1 (-1000 2300)(-800 2300);
WIRE 16 -1 (-1000 2350)(-800 2350);
WIRE 16 -1 (-1000 2350)(-1000 2400);
WIRE 16 -1 (-1000 2400)(-800 2400);
WIRE 16 -1 (-1350 2400)(-1000 2400);
WIRE 16 -1 (-1350 2500)(-1350 2400);
WIRE 16 -1 (2500 3500)(2500 3550);
WIRE 16 -1 (2500 3450)(2500 3500);
WIRE 16 -1 (2500 3500)(2300 3500);
WIRE 16 -1 (2500 3550)(2300 3550);
WIRE 16 -1 (2500 3400)(2500 3450);
WIRE 16 -1 (2500 3450)(2300 3450);
WIRE 16 -1 (2500 3350)(2500 3400);
WIRE 16 -1 (2500 3400)(2300 3400);
WIRE 16 -1 (2500 3300)(2500 3350);
WIRE 16 -1 (2500 3350)(2300 3350);
WIRE 16 -1 (2500 3250)(2500 3300);
WIRE 16 -1 (2500 3300)(2300 3300);
WIRE 16 -1 (2500 3200)(2500 3250);
WIRE 16 -1 (2500 3250)(2300 3250);
WIRE 16 -1 (2500 3150)(2500 3200);
WIRE 16 -1 (2500 3200)(2300 3200);
WIRE 16 -1 (2500 3100)(2500 3150);
WIRE 16 -1 (2500 3150)(2300 3150);
WIRE 16 -1 (2500 3100)(2300 3100);
WIRE 16 -1 (2500 3050)(2500 3100);
WIRE 16 -1 (2500 3000)(2500 3050);
WIRE 16 -1 (2500 3050)(2300 3050);
WIRE 16 -1 (2500 2950)(2500 3000);
WIRE 16 -1 (2500 3000)(2300 3000);
WIRE 16 -1 (2500 2900)(2500 2950);
WIRE 16 -1 (2500 2950)(2300 2950);
WIRE 16 -1 (2500 2850)(2500 2900);
WIRE 16 -1 (2500 2900)(2300 2900);
WIRE 16 -1 (2500 2800)(2500 2850);
WIRE 16 -1 (2500 2850)(2300 2850);
WIRE 16 -1 (2500 2750)(2500 2800);
WIRE 16 -1 (2500 2800)(2300 2800);
WIRE 16 -1 (2500 2700)(2500 2750);
WIRE 16 -1 (2500 2750)(2300 2750);
WIRE 16 -1 (2500 2650)(2500 2700);
WIRE 16 -1 (2500 2700)(2300 2700);
WIRE 16 -1 (2500 2600)(2500 2650);
WIRE 16 -1 (2500 2650)(2300 2650);
WIRE 16 -1 (2500 2600)(2300 2600);
WIRE 16 -1 (2500 2550)(2500 2600);
WIRE 16 -1 (2500 2500)(2500 2550);
WIRE 16 -1 (2500 2550)(2300 2550);
WIRE 16 -1 (2500 2450)(2500 2500);
WIRE 16 -1 (2500 2500)(2300 2500);
WIRE 16 -1 (2500 2400)(2500 2450);
WIRE 16 -1 (2500 2450)(2300 2450);
WIRE 16 -1 (2500 2350)(2500 2400);
WIRE 16 -1 (2500 2400)(2300 2400);
WIRE 16 -1 (2500 2300)(2500 2350);
WIRE 16 -1 (2500 2350)(2300 2350);
WIRE 16 -1 (2500 2250)(2500 2300);
WIRE 16 -1 (2500 2300)(2300 2300);
WIRE 16 -1 (2500 2200)(2500 2250);
WIRE 16 -1 (2500 2250)(2300 2250);
WIRE 16 -1 (2500 2150)(2500 2200);
WIRE 16 -1 (2500 2200)(2300 2200);
WIRE 16 -1 (2500 2100)(2500 2150);
WIRE 16 -1 (2500 2150)(2300 2150);
WIRE 16 -1 (2500 2050)(2500 2100);
WIRE 16 -1 (2500 2100)(2300 2100);
WIRE 16 -1 (2500 2050)(2300 2050);
WIRE 16 -1 (2500 2000)(2500 2050);
WIRE 16 -1 (2500 1950)(2500 2000);
WIRE 16 -1 (2500 2000)(2300 2000);
WIRE 16 -1 (2500 1900)(2500 1950);
WIRE 16 -1 (2500 1950)(2300 1950);
WIRE 16 -1 (2500 1850)(2500 1900);
WIRE 16 -1 (2500 1900)(2300 1900);
WIRE 16 -1 (2500 1800)(2500 1850);
WIRE 16 -1 (2500 1850)(2300 1850);
WIRE 16 -1 (2500 1750)(2500 1800);
WIRE 16 -1 (2500 1800)(2300 1800);
WIRE 16 -1 (2500 1700)(2500 1750);
WIRE 16 -1 (2500 1750)(2300 1750);
WIRE 16 -1 (2500 1650)(2500 1700);
WIRE 16 -1 (2500 1700)(2300 1700);
WIRE 16 -1 (2500 1600)(2500 1650);
WIRE 16 -1 (2500 1650)(2300 1650);
WIRE 16 -1 (2500 1550)(2500 1600);
WIRE 16 -1 (2500 1600)(2300 1600);
WIRE 16 -1 (2500 1550)(2300 1550);
WIRE 16 -1 (2500 1500)(2500 1550);
WIRE 16 -1 (2500 1450)(2500 1500);
WIRE 16 -1 (2500 1500)(2300 1500);
WIRE 16 -1 (2500 1400)(2500 1450);
WIRE 16 -1 (2500 1450)(2300 1450);
WIRE 16 -1 (2500 1350)(2500 1400);
WIRE 16 -1 (2500 1400)(2300 1400);
WIRE 16 -1 (2500 1300)(2500 1350);
WIRE 16 -1 (2500 1350)(2300 1350);
WIRE 16 -1 (2500 1250)(2500 1300);
WIRE 16 -1 (2500 1300)(2300 1300);
WIRE 16 -1 (2500 1150)(2500 1250);
WIRE 16 -1 (2500 1250)(2300 1250);
WIRE 16 -1 (-2950 1850)(-5200 1850);
WIRE 16 -1 (-5200 1850)(-5200 1775);
WIRE 16 -1 (-4650 1300)(-4650 1200);
WIRE 16 -1 (-2950 1800)(-3100 1800);
WIRE 16 -1 (-3100 1900)(-3100 1800);
WIRE 16 -1 (-2950 1900)(-3100 1900);
WIRE 16 -1 (-3100 1900)(-3100 1950);
WIRE 16 -1 (-2950 1950)(-3100 1950);
WIRE 16 -1 (-3100 1950)(-5200 1950);
WIRE 16 -1 (-5200 1950)(-5200 2050);
WIRE 16 -1 (-1000 2650)(-800 2650);
WIRE 16 -1 (-1000 2650)(-1000 2700);
WIRE 16 -1 (-1000 2700)(-800 2700);
WIRE 16 -1 (-1000 2700)(-1000 2750);
WIRE 16 -1 (-1000 2750)(-800 2750);
WIRE 16 -1 (-1000 2750)(-1000 2800);
WIRE 16 -1 (-1000 2800)(-1000 2850);
WIRE 16 -1 (-1000 2800)(-800 2800);
WIRE 16 -1 (-1000 2850)(-800 2850);
WIRE 16 -1 (-1000 2975)(-1000 2850);
WIRE 16 -1 (200 2800)(400 2800);
WIRE 16 -1 (400 2800)(400 2850);
WIRE 16 -1 (200 2850)(400 2850);
WIRE 16 -1 (400 2850)(400 2950);
WIRE 16 -1 (1100 3550)(1300 3550);
WIRE 16 -1 (1100 3500)(1100 3550);
WIRE 16 -1 (1100 3500)(1300 3500);
WIRE 16 -1 (1100 3450)(1100 3500);
WIRE 16 -1 (1100 3450)(1300 3450);
WIRE 16 -1 (1100 3400)(1100 3450);
WIRE 16 -1 (1100 3400)(1300 3400);
WIRE 16 -1 (1100 3350)(1100 3400);
WIRE 16 -1 (1100 3350)(1300 3350);
WIRE 16 -1 (1100 3300)(1100 3350);
WIRE 16 -1 (1100 3300)(1300 3300);
WIRE 16 -1 (1100 3250)(1100 3300);
WIRE 16 -1 (1100 3250)(1300 3250);
WIRE 16 -1 (1100 3200)(1100 3250);
WIRE 16 -1 (1100 3200)(1300 3200);
WIRE 16 -1 (1100 3150)(1100 3200);
WIRE 16 -1 (1100 3150)(1300 3150);
WIRE 16 -1 (1100 3100)(1100 3150);
WIRE 16 -1 (1100 3100)(1300 3100);
WIRE 16 -1 (1100 3050)(1100 3100);
WIRE 16 -1 (1100 3050)(1300 3050);
WIRE 16 -1 (1100 3000)(1100 3050);
WIRE 16 -1 (1100 3000)(1300 3000);
WIRE 16 -1 (1100 2950)(1100 3000);
WIRE 16 -1 (1100 2950)(1300 2950);
WIRE 16 -1 (1100 2900)(1100 2950);
WIRE 16 -1 (1100 2900)(1300 2900);
WIRE 16 -1 (1100 2850)(1100 2900);
WIRE 16 -1 (1100 2850)(1300 2850);
WIRE 16 -1 (1100 2800)(1100 2850);
WIRE 16 -1 (1100 2800)(1300 2800);
WIRE 16 -1 (1100 2750)(1100 2800);
WIRE 16 -1 (1100 2750)(1300 2750);
WIRE 16 -1 (1100 2700)(1100 2750);
WIRE 16 -1 (1100 2700)(1300 2700);
WIRE 16 -1 (1100 2650)(1100 2700);
WIRE 16 -1 (1100 2650)(1300 2650);
WIRE 16 -1 (1100 2600)(1100 2650);
WIRE 16 -1 (1100 2600)(1300 2600);
WIRE 16 -1 (1100 2550)(1100 2600);
WIRE 16 -1 (1100 2550)(1300 2550);
WIRE 16 -1 (1100 2500)(1100 2550);
WIRE 16 -1 (1100 2500)(1300 2500);
WIRE 16 -1 (1100 2450)(1100 2500);
WIRE 16 -1 (1100 2450)(1300 2450);
WIRE 16 -1 (1100 2400)(1100 2450);
WIRE 16 -1 (1100 2400)(1300 2400);
WIRE 16 -1 (1100 2350)(1100 2400);
WIRE 16 -1 (1100 2350)(1300 2350);
WIRE 16 -1 (1100 2300)(1100 2350);
WIRE 16 -1 (1100 2300)(1300 2300);
WIRE 16 -1 (1100 2250)(1100 2300);
WIRE 16 -1 (1100 2250)(1300 2250);
WIRE 16 -1 (1100 2200)(1100 2250);
WIRE 16 -1 (1100 2200)(1300 2200);
WIRE 16 -1 (1100 2150)(1100 2200);
WIRE 16 -1 (1100 2150)(1300 2150);
WIRE 16 -1 (1100 2100)(1100 2150);
WIRE 16 -1 (1100 2100)(1300 2100);
WIRE 16 -1 (1100 2050)(1100 2100);
WIRE 16 -1 (1100 2050)(1300 2050);
WIRE 16 -1 (1100 2000)(1100 2050);
WIRE 16 -1 (1100 2000)(1300 2000);
WIRE 16 -1 (1100 1950)(1100 2000);
WIRE 16 -1 (1100 1950)(1300 1950);
WIRE 16 -1 (1100 1900)(1100 1950);
WIRE 16 -1 (1100 1900)(1300 1900);
WIRE 16 -1 (1100 1850)(1100 1900);
WIRE 16 -1 (1100 1850)(1300 1850);
WIRE 16 -1 (1100 1800)(1100 1850);
WIRE 16 -1 (1100 1800)(1300 1800);
WIRE 16 -1 (1100 1750)(1100 1800);
WIRE 16 -1 (1100 1750)(1300 1750);
WIRE 16 -1 (1100 1700)(1100 1750);
WIRE 16 -1 (1100 1700)(1300 1700);
WIRE 16 -1 (1100 1650)(1100 1700);
WIRE 16 -1 (1100 1650)(1300 1650);
WIRE 16 -1 (1100 1600)(1100 1650);
WIRE 16 -1 (1100 1600)(1300 1600);
WIRE 16 -1 (1100 1550)(1100 1600);
WIRE 16 -1 (1100 1550)(1300 1550);
WIRE 16 -1 (1100 1500)(1100 1550);
WIRE 16 -1 (1100 1500)(1300 1500);
WIRE 16 -1 (1100 1450)(1100 1500);
WIRE 16 -1 (1100 1450)(1300 1450);
WIRE 16 -1 (1100 1400)(1100 1450);
WIRE 16 -1 (1100 1400)(1300 1400);
WIRE 16 -1 (1100 1350)(1100 1400);
WIRE 16 -1 (1100 1350)(1300 1350);
WIRE 16 -1 (1100 1300)(1100 1350);
WIRE 16 -1 (1100 1300)(1300 1300);
WIRE 16 -1 (1100 1250)(1100 1300);
WIRE 16 -1 (1100 1250)(1300 1250);
WIRE 16 -1 (1100 1150)(1100 1250);
WIRE 16 -1 (-1000 2500)(-800 2500);
WIRE 16 -1 (-1000 2500)(-1000 2550);
WIRE 16 -1 (-1000 2550)(-800 2550);
WIRE 16 -1 (-1150 2550)(-1000 2550);
WIRE 16 -1 (-1150 2650)(-1150 2550);
WIRE 16 -1 (-2950 1600)(-4650 1600);
FORCEPROP 2 LAST SIG_NAME M_M_VREF
J 0
(-3725 1610);
DISPLAY 0.617021 (-3725 1610);
PAINT ORANGE (-3725 1610);
WIRE 16 -1 (-4650 1600)(-4750 1600);
WIRE 16 -1 (-4650 1600)(-4650 1500);
WIRE 16 -1 (-3800 1500)(-2950 1500);
FORCEPROP 2 LAST SIG_NAME TP_CH_M_DIMM_M1_RFU_2
J 0
(-3750 1510);
DISPLAY 0.617021 (-3750 1510);
PAINT ORANGE (-3750 1510);
FORCEPROP 2 LASTPROP $XRERR UNIQUE?
J 0
(-4040 1500);
DISPLAY 0.638298 (-4040 1500);
PAINT MONO (-4040 1500);
DISPLAY INVISIBLE (-4040 1500);
WIRE 16 -1 (-3800 1400)(-2950 1400);
FORCEPROP 2 LAST SIG_NAME TP_CH_M_DIMM_M1_RFU_0
J 0
(-3750 1410);
DISPLAY 0.617021 (-3750 1410);
PAINT ORANGE (-3750 1410);
FORCEPROP 2 LASTPROP $XRERR UNIQUE?
J 0
(-4040 1400);
DISPLAY 0.638298 (-4040 1400);
PAINT MONO (-4040 1400);
DISPLAY INVISIBLE (-4040 1400);
WIRE 16 -1 (-3800 1450)(-2950 1450);
FORCEPROP 2 LAST SIG_NAME TP_CH_M_DIMM_M1_RFU_1
J 0
(-3750 1460);
DISPLAY 0.617021 (-3750 1460);
PAINT ORANGE (-3750 1460);
FORCEPROP 2 LASTPROP $XRERR UNIQUE?
J 0
(-4040 1450);
DISPLAY 0.638298 (-4040 1450);
PAINT MONO (-4040 1450);
DISPLAY INVISIBLE (-4040 1450);
WIRE 16 -1 (-3750 1700)(-2950 1700);
FORCEPROP 2 LAST SIG_NAME SMB_DDR_KLM_VPP_SCL
J 0
(-3710 1710);
DISPLAY 0.617021 (-3710 1710);
PAINT ORANGE (-3710 1710);
WIRE 16 -1 (-2950 1750)(-3750 1750);
WIRE 16 -1 (-3800 1300)(-2950 1300);
FORCEPROP 2 LAST SIG_NAME FM_ADR_COMPLETE_KLM_N
J 0
(-3750 1310);
DISPLAY 0.617021 (-3750 1310);
PAINT ORANGE (-3750 1310);
WIRE 16 -1 (-3400 2150)(-2950 2150);
WIRE 16 -1 (-3400 2150)(-3400 2450);
WIRE 16 -1 (-3400 2450)(-4125 2450);
FORCEPROP 2 LAST SIG_NAME FM_DIMM_EVENT_COD_N
J 0
(-4121 2452);
DISPLAY 0.617021 (-4121 2452);
PAINT ORANGE (-4121 2452);
WIRE 16 -1 (-2950 2250)(-3300 2250);
WIRE 16 -1 (-3300 2250)(-3300 2700);
WIRE 16 -1 (-3300 2700)(-3750 2700);
FORCEPROP 2 LAST SIG_NAME M_M_PAR
J 0
(-3725 2710);
DISPLAY 0.617021 (-3725 2710);
PAINT ORANGE (-3725 2710);
WIRE 16 -1 (-2950 2200)(-3350 2200);
WIRE 16 -1 (-3350 2200)(-3350 2650);
WIRE 16 -1 (-3350 2650)(-3750 2650);
FORCEPROP 2 LAST SIG_NAME M_KLM_RST_N
J 0
(-3725 2660);
DISPLAY 0.617021 (-3725 2660);
PAINT ORANGE (-3725 2660);
WIRE 16 -1 (-3100 3300)(-2950 3300);
WIRE 16 -1 (-3100 3325)(-3100 3300);
WIRE 16 -1 (-3100 3325)(-3750 3325);
FORCEPROP 2 LAST SIG_NAME M_M_C<2>
J 0
(-3725 3335);
DISPLAY 0.617021 (-3725 3335);
PAINT ORANGE (-3725 3335);
WIRE 16 -1 (-2950 3800)(-3150 3800);
WIRE 16 -1 (-2950 3250)(-3150 3250);
WIRE 16 -1 (-2950 3200)(-3150 3200);
WIRE 16 -1 (-2950 3150)(-3150 3150);
WIRE 16 -1 (-2950 3900)(-3150 3900);
WIRE 16 -1 (-2950 4050)(-3150 4050);
WIRE 16 -1 (-2950 2650)(-3150 2650);
WIRE 16 -1 (-2950 2600)(-3150 2600);
WIRE 16 -1 (-2950 2550)(-3150 2550);
WIRE 16 -1 (-2950 2500)(-3150 2500);
WIRE 16 -1 (-2950 2450)(-3150 2450);
WIRE 16 -1 (-2950 2400)(-3150 2400);
WIRE 16 -1 (-2950 2350)(-3150 2350);
WIRE 16 -1 (-2950 3000)(-3150 3000);
WIRE 16 -1 (-2950 3650)(-3150 3650);
WIRE 16 -1 (-2950 3700)(-3150 3700);
WIRE 16 -1 (-2950 3750)(-3150 3750);
WIRE 16 -1 (-2950 4000)(-3150 4000);
WIRE 16 -1 (-2950 2700)(-3150 2700);
WIRE 16 -1 (-2950 2800)(-3150 2800);
WIRE 16 -1 (-2950 2850)(-3150 2850);
WIRE 16 -1 (-2950 2950)(-3150 2950);
WIRE 16 -1 (-2950 3100)(-3150 3100);
WIRE 16 -1 (-2950 3950)(-3150 3950);
WIRE 16 -1 (-2950 3450)(-3600 3450);
WIRE 16 -1 (-2950 3550)(-3600 3550);
WIRE 16 -1 (-3750 3500)(-2950 3500);
WIRE 16 -1 (-2950 3400)(-3750 3400);
WIRE 16 -1 (-2950 2100)(-3975 2100);
FORCEPROP 2 LAST SIG_NAME M_M_ALERT_N
J 0
(-3925 2110);
DISPLAY 0.617021 (-3925 2110);
PAINT ORANGE (-3925 2110);
WIRE 16 -1 (-2950 2050)(-3950 2050);
FORCEPROP 2 LAST SIG_NAME M_M_ACT_N
J 0
(-3925 2060);
DISPLAY 0.617021 (-3925 2060);
PAINT ORANGE (-3925 2060);
WIRE 16 -1 (-1750 1950)(-1950 1950);
WIRE 16 -1 (-1750 1900)(-1950 1900);
WIRE 16 -1 (-1750 1650)(-1950 1650);
WIRE 16 -1 (-1750 1600)(-1950 1600);
WIRE 16 -1 (-1750 1700)(-1950 1700);
WIRE 16 -1 (-1750 1750)(-1950 1750);
WIRE 16 -1 (-1750 1800)(-1950 1800);
WIRE 16 -1 (-1750 1850)(-1950 1850);
WIRE 16 -1 (-1750 2000)(-1950 2000);
WIRE 16 -1 (-1750 2550)(-1950 2550);
WIRE 16 -1 (-1750 2500)(-1950 2500);
WIRE 16 -1 (-1750 2250)(-1950 2250);
WIRE 16 -1 (-1750 2050)(-1950 2050);
WIRE 16 -1 (-1750 2450)(-1950 2450);
WIRE 16 -1 (-1750 2100)(-1950 2100);
WIRE 16 -1 (-1750 2150)(-1950 2150);
WIRE 16 -1 (-1750 2200)(-1950 2200);
WIRE 16 -1 (-1750 2300)(-1950 2300);
WIRE 16 -1 (-1750 2350)(-1950 2350);
WIRE 16 -1 (-1750 2400)(-1950 2400);
WIRE 16 -1 (-1750 3050)(-1950 3050);
WIRE 16 -1 (-1750 3000)(-1950 3000);
WIRE 16 -1 (-1750 2850)(-1950 2850);
WIRE 16 -1 (-1750 2800)(-1950 2800);
WIRE 16 -1 (-1750 2750)(-1950 2750);
WIRE 16 -1 (-1750 2650)(-1950 2650);
WIRE 16 -1 (-1750 2600)(-1950 2600);
WIRE 16 -1 (-1750 2950)(-1950 2950);
WIRE 16 -1 (-1750 2900)(-1950 2900);
WIRE 16 -1 (-1750 2700)(-1950 2700);
WIRE 16 -1 (-1750 3550)(-1950 3550);
WIRE 16 -1 (-1750 3450)(-1950 3450);
WIRE 16 -1 (-1750 3300)(-1950 3300);
WIRE 16 -1 (-1750 3250)(-1950 3250);
WIRE 16 -1 (-1750 3200)(-1950 3200);
WIRE 16 -1 (-1750 3150)(-1950 3150);
WIRE 16 -1 (-1750 3350)(-1950 3350);
WIRE 16 -1 (-1750 3400)(-1950 3400);
WIRE 16 -1 (-1750 3500)(-1950 3500);
WIRE 16 -1 (-1750 3100)(-1950 3100);
WIRE 16 -1 (-1750 3900)(-1950 3900);
WIRE 16 -1 (-1750 3850)(-1950 3850);
WIRE 16 -1 (-1750 3800)(-1950 3800);
WIRE 16 -1 (-1750 3750)(-1950 3750);
WIRE 16 -1 (-1750 3700)(-1950 3700);
WIRE 16 -1 (-1750 3650)(-1950 3650);
WIRE 16 -1 (-1750 3600)(-1950 3600);
WIRE 16 -1 (-1750 4050)(-1950 4050);
WIRE 16 -1 (-1750 4000)(-1950 4000);
WIRE 16 -1 (-1750 3950)(-1950 3950);
WIRE 16 -1 (-2950 4500)(-3150 4500);
WIRE 16 -1 (-2950 4550)(-3150 4550);
WIRE 16 -1 (-2950 4750)(-3150 4750);
WIRE 16 -1 (-2950 4150)(-3150 4150);
WIRE 16 -1 (-2950 4200)(-3150 4200);
WIRE 16 -1 (-2950 4250)(-3150 4250);
WIRE 16 -1 (-2950 4300)(-3150 4300);
WIRE 16 -1 (-2950 4350)(-3150 4350);
WIRE 16 -1 (-2950 4400)(-3150 4400);
WIRE 16 -1 (-2950 4450)(-3150 4450);
WIRE 16 -1 (-2950 4600)(-3150 4600);
WIRE 16 -1 (-2950 4650)(-3150 4650);
WIRE 16 -1 (-2950 4700)(-3150 4700);
WIRE 16 -1 (-2950 4100)(-3150 4100);
WIRE 16 -1 (-1750 4550)(-1950 4550);
WIRE 16 -1 (-1750 4400)(-1950 4400);
WIRE 16 -1 (-1750 4350)(-1950 4350);
WIRE 16 -1 (-1750 4300)(-1950 4300);
WIRE 16 -1 (-1750 4250)(-1950 4250);
WIRE 16 -1 (-1750 4200)(-1950 4200);
WIRE 16 -1 (-1750 4150)(-1950 4150);
WIRE 16 -1 (-1750 4100)(-1950 4100);
WIRE 16 -1 (-1750 4450)(-1950 4450);
WIRE 16 -1 (-1750 4500)(-1950 4500);
WIRE 16 -1 (-1750 4600)(-1950 4600);
WIRE 16 -1 (-1750 4700)(-1950 4700);
WIRE 16 -1 (-1750 4650)(-1950 4650);
WIRE 16 -1 (-1750 4750)(-1950 4750);
WIRE 16 -1 (850 3400)(450 3400);
WIRE 16 -1 (650 3450)(450 3450);
WIRE 16 -1 (850 3500)(450 3500);
WIRE 16 -1 (650 3550)(450 3550);
WIRE 16 -1 (850 3600)(450 3600);
WIRE 16 -1 (650 3650)(450 3650);
WIRE 16 -1 (850 3700)(450 3700);
WIRE 16 -1 (650 3750)(450 3750);
WIRE 16 -1 (850 3800)(450 3800);
WIRE 16 -1 (650 3850)(450 3850);
WIRE 16 -1 (850 3900)(450 3900);
WIRE 16 -1 (650 3950)(450 3950);
WIRE 16 -1 (850 4000)(450 4000);
WIRE 16 -1 (650 4050)(450 4050);
WIRE 16 -1 (850 4400)(450 4400);
WIRE 16 -1 (650 4450)(450 4450);
WIRE 16 -1 (850 4500)(450 4500);
WIRE 16 -1 (650 4550)(450 4550);
WIRE 16 -1 (850 4600)(450 4600);
WIRE 16 -1 (650 4650)(450 4650);
WIRE 16 -1 (850 4700)(450 4700);
WIRE 16 -1 (650 4750)(450 4750);
WIRE 16 -1 (850 4800)(450 4800);
WIRE 16 -1 (650 4850)(450 4850);
WIRE 16 -1 (850 4900)(450 4900);
WIRE 16 -1 (650 4950)(450 4950);
WIRE 16 -1 (850 5000)(450 5000);
WIRE 16 -1 (650 5050)(450 5050);
WIRE 16 -1 (850 5100)(450 5100);
WIRE 16 -1 (850 4100)(450 4100);
WIRE 16 -1 (650 4150)(450 4150);
WIRE 16 -1 (850 4200)(450 4200);
WIRE 16 -1 (650 4250)(450 4250);
WIRE 16 -1 (850 4300)(450 4300);
WIRE 16 -1 (650 4350)(450 4350);
WIRE 16 -1 (650 5150)(450 5150);
DOT 1 (400 2850);
DOT 1 (-1000 2400);
DOT 1 (-1000 2300);
DOT 1 (-1000 1700);
DOT 1 (-1000 2700);
DOT 1 (-1000 1200);
DOT 1 (-1000 2550);
DOT 1 (-1000 1300);
DOT 1 (-1000 1250);
DOT 1 (-1000 1350);
DOT 1 (-1000 1400);
DOT 1 (-1000 1450);
DOT 1 (-1000 1500);
DOT 1 (-1000 1550);
DOT 1 (-1000 1600);
DOT 1 (-1000 1650);
DOT 1 (-1000 1750);
DOT 1 (-1000 1800);
DOT 1 (-1000 1850);
DOT 1 (-1000 1900);
DOT 1 (-1000 1950);
DOT 1 (-1000 2000);
DOT 1 (-1000 2050);
DOT 1 (-1000 2100);
DOT 1 (-1000 2150);
DOT 1 (-1000 2200);
DOT 1 (-1000 2250);
DOT 1 (-1000 2350);
DOT 1 (-1000 2750);
DOT 1 (-1000 2800);
DOT 1 (-1000 2850);
DOT 1 (-3100 1950);
DOT 1 (1100 1250);
DOT 1 (1100 1300);
DOT 1 (1100 1350);
DOT 1 (1100 1400);
DOT 1 (1100 1450);
DOT 1 (1100 1500);
DOT 1 (1100 1550);
DOT 1 (1100 1600);
DOT 1 (1100 1650);
DOT 1 (1100 1700);
DOT 1 (1100 1750);
DOT 1 (1100 1800);
DOT 1 (1100 1850);
DOT 1 (1100 1900);
DOT 1 (1100 1950);
DOT 1 (1100 2000);
DOT 1 (1100 2050);
DOT 1 (1100 2100);
DOT 1 (1100 2150);
DOT 1 (1100 2200);
DOT 1 (1100 2250);
DOT 1 (1100 2300);
DOT 1 (1100 2350);
DOT 1 (1100 2400);
DOT 1 (1100 2450);
DOT 1 (1100 2500);
DOT 1 (1100 2550);
DOT 1 (1100 2600);
DOT 1 (1100 2650);
DOT 1 (1100 2700);
DOT 1 (1100 2750);
DOT 1 (1100 2800);
DOT 1 (1100 2850);
DOT 1 (1100 2900);
DOT 1 (1100 2950);
DOT 1 (1100 3000);
DOT 1 (1100 3050);
DOT 1 (1100 3100);
DOT 1 (1100 3250);
DOT 1 (1100 3150);
DOT 1 (1100 3200);
DOT 1 (1100 3300);
DOT 1 (1100 3400);
DOT 1 (1100 3450);
DOT 1 (1100 3500);
DOT 1 (2500 1250);
DOT 1 (2500 1300);
DOT 1 (2500 1400);
DOT 1 (2500 1450);
DOT 1 (2500 1500);
DOT 1 (2500 1550);
DOT 1 (2500 1600);
DOT 1 (2500 1650);
DOT 1 (2500 1700);
DOT 1 (2500 1750);
DOT 1 (2500 1800);
DOT 1 (2500 1850);
DOT 1 (2500 1900);
DOT 1 (2500 1950);
DOT 1 (2500 2000);
DOT 1 (2500 2050);
DOT 1 (2500 2100);
DOT 1 (2500 2200);
DOT 1 (2500 2250);
DOT 1 (2500 2300);
DOT 1 (2500 2400);
DOT 1 (2500 2450);
DOT 1 (2500 2500);
DOT 1 (2500 2550);
DOT 1 (2500 2600);
DOT 1 (2500 2700);
DOT 1 (2500 2650);
DOT 1 (2500 2750);
DOT 1 (2500 2800);
DOT 1 (2500 2850);
DOT 1 (2500 2900);
DOT 1 (2500 2950);
DOT 1 (2500 3000);
DOT 1 (2500 3050);
DOT 1 (2500 3100);
DOT 1 (2500 3150);
DOT 1 (2500 3200);
DOT 1 (2500 3250);
DOT 1 (2500 3300);
DOT 1 (2500 3350);
DOT 1 (2500 3400);
DOT 1 (2500 3450);
DOT 1 (2500 3500);
DOT 1 (2500 1350);
DOT 1 (2500 2150);
DOT 1 (2500 2350);
DOT 1 (1100 3350);
DOT 1 (-3100 1900);
DOT 1 (-4650 1600);
FORCENOTE
PLACE CAP NEAR DIMM CONNECTOR
(-5288 1052) 0;
DISPLAY LEFT (-5288 1052);
DISPLAY 1.595745 (-5288 1052);
PAINT PURPLE (-5288 1052);
FORCENOTE
SMBUS ADDR: 0XAA
(-5225 909) 0;
DISPLAY LEFT (-5225 909);
DISPLAY 1.957447 (-5225 909);
PAINT PURPLE (-5225 909);
QUIT
